G04 ================== begin FILE IDENTIFICATION RECORD ==================*
G04 Layout Name:  12432-1.brd*
G04 Film Name:    DIF_REF_BOTTOM*
G04 File Format:  Gerber RS274X*
G04 File Origin:  Cadence Allegro 16.2-S037*
G04 Origin Date:  Wed Oct 17 11:00:24 2012*
G04 *
G04 Layer:  BOARD GEOMETRY/OUTLINE*
G04 Layer:  BOARD GEOMETRY/DIF_REF_BOTTOM*
G04 Layer:  BOARD GEOMETRY/PANEL_OUTLINE*
G04 *
G04 Offset:    (0.00 0.00)*
G04 Mirror:    No*
G04 Mode:      Positive*
G04 Rotation:  0*
G04 FullContactRelief:  No*
G04 UndefLineWidth:     6.00*
G04 ================== end FILE IDENTIFICATION RECORD ====================*
%FSLAX35Y35*MOIN*%
%IR0*IPPOS*OFA0.00000B0.00000*MIA0B0*SFA1.00000B1.00000*%
%ADD10C,.01*%
%ADD11C,.004*%
%ADD12C,.006*%
G75*
%LPD*%
G75*
G54D10*
G01X-78740Y15000D02*
G03X-63740Y0I15000J0D01*
G01X-78740Y15000D02*
Y319646D01*
G01X-63740Y334646D02*
G03X-78740Y319646I0J-15000D01*
G01Y908315D02*
G03X-63740Y893315I15000J0D01*
G01X-78740Y908315D02*
Y1304286D01*
G01X-63740Y1319286D02*
G03X-78740Y1304286I0J-15000D01*
G01Y1892953D02*
G03X-63740Y1877953I15000J0D01*
G01X-78740Y1892953D02*
Y1977126D01*
G01X-63740Y1992126D02*
G03X-78740Y1977126I0J-15000D01*
G01X-7874Y0D02*
X-63740D01*
G01X-7874Y334646D02*
X-63740D01*
G01X-7874Y893315D02*
X-63740D01*
G01X-7874Y1319286D02*
X-63740D01*
G01X-7874Y1877953D02*
X-63740D01*
G01X-7874Y1992126D02*
X-63740D01*
G01X-7874Y17253D02*
Y0D01*
G01X0Y17214D02*
G03X-7874I-3937J0D01*
G01Y41772D02*
Y167110D01*
G01Y41772D02*
G03X0I3937J0D01*
G01Y167110D02*
G03X-7874I-3937J0D01*
G01Y191667D02*
Y308383D01*
G01Y191667D02*
G03X0I3937J0D01*
G01Y308383D02*
G03X-7874I-3937J0D01*
G01Y331986D02*
Y334646D01*
G01Y332003D02*
G03X0I3937J0D01*
G01X-7874Y905988D02*
Y893315D01*
G01X0Y905988D02*
G03X-7874I-3937J0D01*
G01Y1106301D02*
Y933234D01*
G01D02*
G03X0I3937J0D01*
G01Y1106301D02*
G03X-7874I-3937J0D01*
G01Y1280567D02*
Y1129921D01*
G01D02*
G03X0I3937J0D01*
G01Y1280567D02*
G03X-7874I-3937J0D01*
G01Y1309889D02*
Y1319286D01*
G01Y1309889D02*
G03X0I3937J0D01*
G01X-7874Y1889223D02*
Y1877953D01*
G01X0Y1889223D02*
G03X-7874I-3937J0D01*
G01X0D02*
G03X-7874I-3937J0D01*
G01Y1912843D02*
Y1962927D01*
G01Y1912843D02*
G03X0I3937J0D01*
G01Y1962927D02*
G03X-7874I-3937J0D01*
G01X0D02*
G03X-7874I-3937J0D01*
G01Y1986547D02*
Y1992126D01*
G01Y1986547D02*
G03X0I3937J0D01*
G01X3937Y0D02*
X1029528D01*
G01X0Y3937D02*
G03X3937Y0I3937J0D01*
G01X0Y409646D02*
Y3937D01*
G01X3937Y413583D02*
X0Y409646D01*
G01X19882Y413583D02*
X3937D01*
G01Y421063D02*
X19882D01*
G01X0Y425000D02*
X3937Y421063D01*
G01X0Y819094D02*
Y425000D01*
G01X3937Y823031D02*
X0Y819094D01*
G01X19882Y823031D02*
X3937D01*
G01Y830512D02*
X19882D01*
G01X0Y834449D02*
X3937Y830512D01*
G01X0Y1393898D02*
Y834449D01*
G01X3937Y1397835D02*
X0Y1393898D01*
G01X19882Y1397835D02*
X3937D01*
G01Y1405315D02*
X19882D01*
G01X0Y1409252D02*
X3937Y1405315D01*
G01X0Y1803346D02*
Y1409252D01*
G01X3937Y1807283D02*
X0Y1803346D01*
G01X19882Y1807283D02*
X3937D01*
G01Y1814764D02*
X19882D01*
G01X0Y1818701D02*
X3937Y1814764D01*
G01X0Y1988189D02*
Y1818701D01*
G01X3937Y1992126D02*
G03X0Y1988189I0J-3937D01*
G01X1029528Y1992126D02*
X3937D01*
G01X19882Y413583D02*
G03Y421063I0J3740D01*
G01Y823031D02*
G03Y830512I0J3741D01*
G01Y1397835D02*
G03Y1405315I0J3740D01*
G01Y1807283D02*
G03Y1814764I0J3740D01*
G01X989744Y1616083D02*
X1015354D01*
G01X989744D02*
G03Y1611870I0J-2107D01*
G01X1015354D02*
X989744D01*
G01X1033465Y3937D02*
Y1424882D01*
G01X1029528Y0D02*
G03X1033465Y3937I0J3937D01*
G01X1041338Y24677D02*
G03X1033464I-3937J0D01*
G01X1041338D02*
G03X1033464I-3937J0D01*
G01Y48297D02*
G03X1041338I3937J0D01*
G01Y217343D02*
G03X1033464I-3937J0D01*
G01X1041338D02*
G03X1033464I-3937J0D01*
G01Y240964D02*
G03X1041338I3937J0D01*
G01X1033464D02*
G03X1041338I3937J0D01*
G01Y445039D02*
G03X1033464I-3937J0D01*
G01X1041338D02*
G03X1033464I-3937J0D01*
G01Y468659D02*
G03X1041338I3937J0D01*
G01X1033464D02*
G03X1041338I3937J0D01*
G01Y697473D02*
G03X1033464I-3937J0D01*
G01X1041338D02*
G03X1033464I-3937J0D01*
G01Y721093D02*
G03X1041338I3937J0D01*
G01X1033464D02*
G03X1041338I3937J0D01*
G01Y996852D02*
G03X1033464I-3937J0D01*
G01X1041338D02*
G03X1033464I-3937J0D01*
G01Y1020472D02*
G03X1041338I3937J0D01*
G01X1033464D02*
G03X1041338I3937J0D01*
G01Y1344060D02*
G03X1033464I-3937J0D01*
G01X1041338D02*
G03X1033464I-3937J0D01*
G01Y1367680D02*
G03X1041338I3937J0D01*
G01X1033464D02*
G03X1041338I3937J0D01*
G01X1033465Y1424882D02*
X1029528Y1428819D01*
G01X1019291Y1433740D02*
Y1607933D01*
G01Y1433740D02*
G03X1024213Y1428819I4921J0D01*
G01X1029528D02*
X1024213D01*
G01X1015354Y1616083D02*
X1019291Y1620020D01*
G01Y1607933D02*
X1015354Y1611870D01*
G01X1019291Y1620020D02*
Y1676496D01*
G01X1029528Y1681417D02*
X1033465Y1685354D01*
G01X1024213Y1681417D02*
G03X1019291Y1676496I-1J-4921D01*
G01X1033465Y1685354D02*
Y1988189D01*
G01X1024213Y1681417D02*
X1029528D01*
G01X1041338Y1739719D02*
G03X1033464I-3937J0D01*
G01X1041338D02*
G03X1033464I-3937J0D01*
G01Y1763339D02*
G03X1041338I3937J0D01*
G01X1033464D02*
G03X1041338I3937J0D01*
G01Y1959242D02*
G03X1033464I-3937J0D01*
G01X1041338D02*
G03X1033464I-3937J0D01*
G01X1033465Y1988189D02*
G03X1029528Y1992126I-3937J0D01*
G01X1033464Y1982862D02*
G03X1041338I3937J0D01*
G01Y24677D02*
Y0D01*
G01D02*
X1097205D01*
G01X1041338Y217343D02*
Y48297D01*
G01Y445039D02*
Y240964D01*
G01Y697473D02*
Y468601D01*
G01Y996852D02*
Y721093D01*
G01Y1344060D02*
Y1020472D01*
G01Y1367680D02*
Y1393701D01*
G01D02*
X1097205D01*
G01X1041338Y1733129D02*
Y1716536D01*
G01X1065043D02*
X1041338D01*
G01Y1739719D02*
Y1731536D01*
G01Y1959242D02*
Y1763310D01*
G01Y1992126D02*
X1097205D01*
G01X1041338Y1982862D02*
Y1992126D01*
G01X1056338Y1716536D02*
X1097205D01*
G01Y0D02*
G03X1112205Y15000I0J15000D01*
G01Y1378701D02*
G03X1097205Y1393701I-15000J0D01*
G01Y1716536D02*
G03X1112205Y1731536I0J15000D01*
G01Y1977126D02*
G03X1097205Y1992126I-15000J0D01*
G01X1112205Y648419D02*
Y15000D01*
G01Y656293D02*
G03Y648419I0J-3937D01*
G01Y1378701D02*
Y656293D01*
G01Y1977126D02*
Y1731536D01*
G54D11*
G01X11069Y379915D02*
X19151D01*
G01X11069Y375978D02*
X18972D01*
G01X11069Y395663D02*
X19664D01*
G01X11069Y391726D02*
X19494D01*
G01X11069Y411411D02*
X11075Y411417D01*
G01D02*
X19947D01*
G01X11069Y407474D02*
X19829D01*
G01X11069Y431098D02*
X19787D01*
G01X11069Y450783D02*
X19727D01*
G01X19827Y446852D02*
X11075D01*
G01D02*
X11069Y446846D01*
G01Y435035D02*
X19410D01*
G01X11069Y466531D02*
X19094D01*
G01X11069Y462594D02*
X19394D01*
G01X11069Y494090D02*
X19640D01*
G01X11069Y482279D02*
X19394D01*
G01X11069Y478342D02*
X19194D01*
G01X11069Y513775D02*
X18994D01*
G01X19959Y509844D02*
X11075D01*
G01D02*
X11069Y509838D01*
G01Y498027D02*
X19554D01*
G01X11069Y529523D02*
X19294D01*
G01X11069Y525586D02*
X19553D01*
G01X11069Y580704D02*
X18349D01*
G01D02*
X18355Y580710D01*
G01D02*
G03X20472Y581587I0J2994D01*
G01X11069Y584641D02*
X18459D01*
G01D02*
X18465Y584647D01*
G01D02*
G02X20474Y583815I0J-2841D01*
G01X11069Y616137D02*
X18274D01*
G01D02*
X18280Y616143D01*
G01D02*
G02X20484Y615230I0J-3117D01*
G01X11069Y612200D02*
X18295D01*
G01D02*
X18301Y612206D01*
G01D02*
G03X20537Y613132I0J3162D01*
G01X11069Y631885D02*
X19632D01*
G01X11069Y627948D02*
X19683D01*
G01X11069Y643696D02*
X18472D01*
G01D02*
X18478Y643702D01*
G01D02*
G03X20651Y644602I0J3073D01*
G01X11069Y647633D02*
X19613D01*
G01X11069Y663381D02*
X11075Y663387D01*
G01D02*
X19862D01*
G01X11069Y659444D02*
X19162D01*
G01X11069Y679129D02*
X18347D01*
G01D02*
X18353Y679135D01*
G01D02*
G02X20569Y678217I0J-3134D01*
G01X11069Y675192D02*
X18982D01*
G01X11069Y1360230D02*
X19020D01*
G01X11069Y1364167D02*
X18899D01*
G01X11069Y1379915D02*
X11075Y1379921D01*
G01D02*
X19953D01*
G01X11069Y1375978D02*
X18519D01*
G01D02*
X18525Y1375984D01*
G01D02*
G03X21099Y1377050I0J3640D01*
G01X11069Y1395663D02*
X19574D01*
G01X20051Y1391732D02*
X11075D01*
G01D02*
X11069Y1391726D01*
G01Y1419287D02*
X18858D01*
G01D02*
X18864Y1419293D01*
G01X11069Y1415350D02*
X19322D01*
G01X11069Y1446846D02*
X19128D01*
G01X11069Y1435035D02*
X18940D01*
G01X11069Y1431098D02*
X19467D01*
G01X11069Y1466531D02*
X18502D01*
G01D02*
X18508Y1466537D01*
G01D02*
G02X20630Y1465658I0J-3001D01*
G01X11069Y1462594D02*
X18494D01*
G01D02*
X18500Y1462600D01*
G01D02*
G03X20721Y1463520I0J3141D01*
G01X11069Y1450783D02*
X19209D01*
G01X11069Y1482279D02*
X19254D01*
G01X11069Y1478342D02*
X19186D01*
G01X11069Y1498027D02*
X19381D01*
G01X19783Y1494096D02*
X11075D01*
G01D02*
X11069Y1494090D01*
G01Y1509838D02*
X19440D01*
G01X11069Y1513775D02*
X19183D01*
G01X11069Y1568893D02*
X18103D01*
G01D02*
X18109Y1568899D01*
G01D02*
G02X20265Y1568006I0J-3049D01*
G01X11069Y1564956D02*
X18511D01*
G01D02*
X18517Y1564962D01*
G01D02*
G03X20559Y1565808I0J2888D01*
G01X11069Y1616137D02*
X18513D01*
G01D02*
X18519Y1616143D01*
G01D02*
G02X20617Y1615274I0J-2967D01*
G01X11069Y1612200D02*
X18566D01*
G01D02*
X18572Y1612206D01*
G01D02*
G03X20624Y1613056I0J2902D01*
G01X11069Y1600389D02*
X17988D01*
G01D02*
X17994Y1600395D01*
G01D02*
G02X20654Y1599293I0J-3762D01*
G01X11069Y1596452D02*
X18857D01*
G01D02*
X18863Y1596458D01*
G01X11069Y1631885D02*
X19367D01*
G01X11069Y1627948D02*
X18998D01*
G01X11069Y1647633D02*
X18407D01*
G01D02*
X18413Y1647639D01*
G01D02*
G02X20740Y1646675I0J-3291D01*
G01X11069Y1643696D02*
X18566D01*
G01D02*
X18572Y1643702D01*
G01D02*
G03X20626Y1644553I0J2905D01*
G01X11069Y1659444D02*
X19044D01*
G01X11069Y1663381D02*
X18532D01*
G01D02*
X18538Y1663387D01*
G01D02*
G02X20590Y1662537I0J-2902D01*
G01X32222Y377027D02*
X60099Y349150D01*
G01X30929Y376481D02*
X59429Y347981D01*
G01X19151Y379915D02*
X19157Y379921D01*
G01D02*
G02X20929Y379187I0J-2506D01*
G01D02*
G03X22385Y378584I1456J1456D01*
G01D02*
X28499D01*
G01D02*
G02X32196Y377052I-1J-5229D01*
G01D02*
X32222Y377027D01*
G01X18972Y375978D02*
X18978Y375984D01*
G01D02*
G03X20716Y376704I0J2458D01*
G01D02*
X20869Y376858D01*
G01D02*
G02X21899Y377284I1029J-1030D01*
G01D02*
X28990D01*
G01D02*
G02X30929Y376481I0J-2742D01*
G01X26299Y387629D02*
X26857Y387071D01*
G01D02*
G03X28499Y386391I1642J1642D01*
G01D02*
X30299D01*
G01D02*
G02X31935Y385714I1J-2313D01*
G01D02*
X31948Y385700D01*
G01D02*
X63242Y354408D01*
G01X26299Y383854D02*
X26926Y384481D01*
G01D02*
G02X28399Y385091I1473J-1473D01*
G01D02*
X30299D01*
G01D02*
G02X31015Y384795I1J-1012D01*
G01D02*
X31479Y384330D01*
G01D02*
X62322Y353488D01*
G01X33149Y392700D02*
X65597Y360252D01*
G01X32229Y391781D02*
X64952Y359058D01*
G01X19664Y395663D02*
X19670Y395669D01*
G01D02*
G02X20539Y395309I0J-1229D01*
G01D02*
X21199Y394650D01*
G01D02*
G03X21967Y394332I768J768D01*
G01D02*
X29209D01*
G01D02*
G02X33149Y392700I0J-5572D01*
G01X19494Y391726D02*
X19500Y391732D01*
G01D02*
G03X19889Y391893I0J550D01*
G01D02*
X20766Y392770D01*
G01D02*
G02X21399Y393032I633J-633D01*
G01D02*
X29209D01*
G01D02*
G02X32229Y391781I0J-4272D01*
G01X26299Y403376D02*
X27162Y402513D01*
G01D02*
G03X28067Y402138I905J905D01*
G01D02*
X30418D01*
G01D02*
G02X33035Y401054I0J-3701D01*
G01D02*
X70262Y363827D01*
G01X26299Y399601D02*
G02X27536Y400838I1237J0D01*
G01D02*
X30862D01*
G01D02*
G02X31799Y400450I0J-1325D01*
G01D02*
X69342Y362907D01*
G01X19947Y411417D02*
G02X21304Y410855I0J-1919D01*
G01D02*
X21504Y410655D01*
G01D02*
G03X22699Y410160I1195J1195D01*
G01D02*
X34174D01*
G01D02*
G02X36248Y409301I0J-2933D01*
G01D02*
X74948Y370601D01*
G01X19829Y407474D02*
X19835Y407480D01*
G01D02*
G03X20849Y407900I0J1434D01*
G01D02*
X21449Y408500D01*
G01D02*
G02X22318Y408860I869J-869D01*
G01D02*
X34173D01*
G01D02*
G02X35329Y408381I0J-1635D01*
G01D02*
X74229Y369481D01*
G01X19787Y431098D02*
X19793Y431104D01*
G01D02*
G03X20607Y431441I0J1151D01*
G01D02*
X21157Y431991D01*
G01D02*
G02X22154Y432404I997J-997D01*
G01D02*
X67583D01*
G01X26524Y426720D02*
X26598Y426647D01*
G01D02*
G03X28499Y425859I1902J1901D01*
G01D02*
X29699D01*
G01D02*
G02X32653Y424636I1J-4177D01*
G01D02*
X32718Y424570D01*
G01D02*
X78068Y379220D01*
G01X26399Y423322D02*
Y423859D01*
G01D02*
G02X27099Y424559I700J0D01*
G01D02*
X30170D01*
G01D02*
G02X31399Y424050I0J-1738D01*
G01D02*
X77399Y378050D01*
G01X19727Y450783D02*
X19733Y450789D01*
G01D02*
G02X20585Y450436I0J-1205D01*
G01D02*
X21135Y449886D01*
G01D02*
G03X22069Y449499I934J934D01*
G01D02*
X35923D01*
G01D02*
G03X40150Y451250I0J5978D01*
G01X41069Y450331D02*
G02X35924Y448199I-5147J5146D01*
G01D02*
X22372D01*
G01D02*
G03X21424Y447933I0J-1823D01*
G01D02*
G03X21083Y447665I948J-1557D01*
G01D02*
X20583Y447165D01*
G01D02*
G02X19827Y446852I-756J756D01*
G01X19410Y435035D02*
X19416Y435041D01*
G01D02*
G02X20811Y434463I0J-1973D01*
G01D02*
X21061Y434213D01*
G01D02*
G03X22290Y433704I1229J1229D01*
G01D02*
X67499D01*
G01X26599Y442749D02*
G03X29126Y441512I2601J2113D01*
G01D02*
X153699D01*
G01X26492Y439350D02*
G02X29099Y440212I2607J-3511D01*
G01D02*
X35179D01*
G01D02*
G02X35385Y440006I0J-206D01*
G01D02*
G03X35591Y439800I206J0D01*
G01D02*
X37579D01*
G01D02*
G03X37785Y440006I0J206D01*
G01D02*
G02X37991Y440212I206J0D01*
G01D02*
X153699D01*
G01X26799Y458497D02*
G03X28037Y457259I1238J0D01*
G01D02*
X36375D01*
G01D02*
G03X39250Y458450I0J4066D01*
G01D02*
X44249Y463449D01*
G01X40169Y457531D02*
G02X36376Y455959I-3795J3794D01*
G01D02*
X28008D01*
G01D02*
G03X26899Y454850I0J-1109D01*
G01X19094Y466531D02*
X19100Y466537D01*
G01D02*
G02X20022Y466155I0J-1304D01*
G01D02*
X20511Y465666D01*
G01D02*
G03X21636Y465200I1125J1125D01*
G01D02*
X23800D01*
G01D02*
G02X25806Y464757I0J-4764D01*
G01D02*
G03X26499Y465200I205J443D01*
G01D02*
Y466250D01*
G01X19394Y462594D02*
X19400Y462600D01*
G01D02*
G03X19908Y462811I-1J719D01*
G01D02*
X20634Y463536D01*
G01D02*
G02X21513Y463900I879J-879D01*
G01D02*
X23799D01*
G01D02*
G02X26248Y462885I-1J-3464D01*
G01D02*
X26486Y462648D01*
G01X19640Y494090D02*
X19646Y494096D01*
G01D02*
G03X20711Y494537I0J1506D01*
G01D02*
X20861Y494687D01*
G01D02*
G02X22573Y495396I1712J-1712D01*
G01D02*
X39269D01*
G01D02*
G03X43571Y497178I0J6084D01*
G01X19394Y482279D02*
X19400Y482285D01*
G01D02*
G02X19800Y482120I1J-565D01*
G01D02*
X20486Y481433D01*
G01D02*
G03X21657Y480948I1171J1171D01*
G01D02*
X23699D01*
G01D02*
G02X25744Y480467I3J-4575D01*
G01D02*
G03X26515Y480944I238J477D01*
G01D02*
Y481798D01*
G01X19194Y478342D02*
X19200Y478348D01*
G01D02*
G03X19991Y478675I1J1118D01*
G01D02*
X20503Y479188D01*
G01D02*
G02X21614Y479648I1111J-1111D01*
G01D02*
X23699D01*
G01D02*
G02X26014Y478689I0J-3274D01*
G01D02*
X26299Y478404D01*
G01X18994Y513775D02*
X19000Y513781D01*
G01D02*
G02X20330Y513230I0J-1881D01*
G01D02*
X20906Y512654D01*
G01D02*
G03X21616Y512360I710J710D01*
G01D02*
X24135D01*
G01D02*
G03X24922Y512686I0J1113D01*
G01D02*
G03X25329Y512995I-923J1639D01*
G01D02*
X26441Y514107D01*
G01D02*
G03X27199Y515937I-1830J1830D01*
G01D02*
Y519980D01*
G01X28499D02*
Y515938D01*
G01D02*
G02X27360Y513188I-3888J-1D01*
G01D02*
Y513187D01*
G01D02*
X26861Y512688D01*
G01D02*
X26602Y512430D01*
G01D02*
G02X26058Y511968I-3104J3103D01*
G01D02*
G02X23866Y511060I-2192J2192D01*
G01D02*
X22170D01*
G01D02*
G03X21453Y510763I0J-1014D01*
G01D02*
X21222Y510531D01*
G01D02*
X20942Y510251D01*
G01D02*
G02X19959Y509844I-983J983D01*
G01X19554Y498027D02*
X19560Y498033D01*
G01D02*
G02X20707Y497558I0J-1622D01*
G01D02*
G03X22788Y496696I2081J2081D01*
G01D02*
X39693D01*
G01D02*
G03X42351Y497797I0J3759D01*
G01X40318Y504503D02*
X28999D01*
G01D02*
G02X26674Y505466I0J3288D01*
G01D02*
X26399Y505741D01*
G01X39964Y503203D02*
X27636D01*
G01D02*
G03X26399Y501966I0J-1237D01*
G01X27199Y519980D02*
G02X27740Y521811I3366J1D01*
G01D02*
X27754Y521832D01*
G01D02*
G02X28031Y522175I1761J-1139D01*
G01D02*
X192400Y764246D01*
G01X193499Y763550D02*
X29104Y521441D01*
G01D02*
G03X28499Y519980I1460J-1460D01*
G01X83417Y580774D02*
X39487Y521271D01*
G01D02*
Y521259D01*
G01D02*
X39196Y520973D01*
G01D02*
X38136Y519913D01*
G01D02*
G02X37136I-500J500D01*
G01D02*
G02X36499Y521451I1538J1538D01*
G01D02*
Y521550D01*
G01X40108Y520045D02*
X38785Y518722D01*
G01D02*
G02X36499Y517775I-2286J2286D01*
G01X19294Y529523D02*
X19300Y529529D01*
G01D02*
G02X20275Y529125I0J-1379D01*
G01D02*
X20648Y528751D01*
G01D02*
G03X21999Y528192I1350J1351D01*
G01D02*
X25099D01*
G01D02*
G03X25765Y528468I0J942D01*
G01D02*
X26599Y529302D01*
G01X19553Y525586D02*
X19559Y525592D01*
G01D02*
G03X20771Y526094I0J1714D01*
G01D02*
G02X22699Y526892I1927J-1928D01*
G01D02*
X24399D01*
G01D02*
G02X26031Y526216I0J-2308D01*
G01D02*
X26599Y525648D01*
G01X20474Y583815D02*
G03X21693Y583310I1219J1219D01*
G01D02*
X28860D01*
G01D02*
G03X31249Y584300I0J3377D01*
G01D02*
X36998Y590049D01*
G01D02*
Y590050D01*
G01D02*
X82572Y635624D01*
G01X20472Y581587D02*
G02X21493Y582010I1021J-1021D01*
G01D02*
X28861D01*
G01D02*
G03X32168Y583380I0J4677D01*
G01D02*
X83492Y634704D01*
G01X20484Y615230D02*
G03X21508Y614806I1024J1024D01*
G01D02*
X50213D01*
G01X20537Y613132D02*
G02X21440Y613506I903J-903D01*
G01D02*
X50212D01*
G01X47689Y622680D02*
X30341D01*
G01D02*
G02X27499Y623857I0J4019D01*
G01Y620203D02*
G02X30341Y621380I2842J-2842D01*
G01D02*
X47689D01*
G01X19632Y631885D02*
X19638Y631891D01*
G01D02*
G02X20596Y631494I0J-1355D01*
G01D02*
G03X22867Y630554I2270J2271D01*
G01D02*
X54748D01*
G01X19683Y627948D02*
X19689Y627954D01*
G01D02*
G03X20737Y628388I0J1482D01*
G01D02*
G02X22828Y629254I2091J-2091D01*
G01D02*
X54749D01*
G01X51650Y638427D02*
X29410D01*
G01D02*
G02X26568Y639604I0J4019D01*
G01X51649Y637127D02*
X29410D01*
G01D02*
G03X26568Y635950I0J-4019D01*
G01X19613Y647633D02*
X19619Y647639D01*
G01D02*
G02X20640Y647216I0J-1444D01*
G01D02*
G02X21121Y646834I-1418J-2279D01*
G01D02*
G03X22867Y646302I1747J2602D01*
G01D02*
X50499D01*
G01X20651Y644602D02*
G02X21617Y645002I966J-966D01*
G01D02*
X50499D01*
G01X46584Y654350D02*
X27982D01*
G01D02*
G02X27499Y654550I0J683D01*
G01D02*
G02X26999Y655757I1207J1207D01*
G01D02*
Y656550D01*
G01X46585Y653050D02*
X29376D01*
G01D02*
G03X26737Y651957I0J-3732D01*
G01X19862Y663387D02*
G02X21339Y662775I0J-2089D01*
G01D02*
X21701Y662412D01*
G01D02*
G03X22577Y662050I875J876D01*
G01D02*
X40199D01*
G01X19162Y659444D02*
X19168Y659450D01*
G01D02*
G03X21099Y660250I0J2731D01*
G01D02*
G02X22306Y660750I1207J-1207D01*
G01D02*
X40199D01*
G01X38199Y687170D02*
Y673550D01*
G01D02*
G02X34999Y670350I-3200J0D01*
G01D02*
X29500D01*
G01D02*
G02X27687Y671101I0J2564D01*
G01X39499Y687169D02*
Y673550D01*
G01D02*
G02X34999Y669050I-4500J0D01*
G01D02*
X28999D01*
G01D02*
G03X27687Y667738I0J-1312D01*
G01D02*
Y667447D01*
G01X20569Y678217D02*
G03X21535Y677817I966J966D01*
G01D02*
X26437D01*
G01D02*
G03X30500Y679500I0J5746D01*
G01D02*
X32427Y681427D01*
G01D02*
G03X33700Y684500I-3073J3073D01*
G01D02*
Y691380D01*
G01X18982Y675192D02*
X18988Y675198D01*
G01D02*
G03X20200Y675700I0J1714D01*
G01D02*
X20650Y676151D01*
G01D02*
G02X21533Y676516I883J-886D01*
G01D02*
G03X21536Y676517I-842J2531D01*
G01D02*
X26438D01*
G01D02*
G03X31419Y678581I-2J7046D01*
G01D02*
Y678580D01*
G01D02*
X32919Y680080D01*
G01D02*
X32920D01*
G01D02*
X33347Y680507D01*
G01D02*
G03X35000Y684499I-3994J3992D01*
G01D02*
Y691379D01*
G01X40496Y695052D02*
G03X38199Y687170I12383J-7884D01*
G01X41592Y694354D02*
G03X39499Y687169I11287J-7185D01*
G01X33700Y691380D02*
G02X35581Y695919I6421J-2D01*
G01D02*
X35580D01*
G01D02*
X93330Y753669D01*
G01X35000Y691379D02*
G02X36500Y695000I5121J0D01*
G01D02*
X94249Y752749D01*
G01X18905Y1364173D02*
G02X20897Y1363348I0J-2817D01*
G01D02*
G03X22133Y1362836I1236J1236D01*
G01D02*
X93638D01*
G01X19020Y1360230D02*
X19026Y1360236D01*
G01D02*
G03X21187Y1361131I0J3056D01*
G01D02*
G02X22165Y1361536I978J-978D01*
G01D02*
X96745D01*
G01X18899Y1364167D02*
X18905Y1364173D01*
G01X25507Y1372045D02*
X25660Y1371892D01*
G01D02*
G03X28499Y1370716I2839J2839D01*
G01D02*
X80279D01*
G01X25558Y1368447D02*
G02X27897Y1369416I2339J-2339D01*
G01D02*
X30194D01*
G01D02*
G02X30502Y1369108I0J-308D01*
G01D02*
G03X30810Y1368800I308J0D01*
G01D02*
X32594D01*
G01D02*
G03X32902Y1369108I0J308D01*
G01D02*
G02X33210Y1369416I308J0D01*
G01D02*
X34994D01*
G01D02*
G02X35302Y1369108I0J-308D01*
G01D02*
G03X35610Y1368800I308J0D01*
G01D02*
X37394D01*
G01D02*
G03X37702Y1369108I0J308D01*
G01D02*
G02X38010Y1369416I308J0D01*
G01D02*
X52004D01*
G01X19953Y1379921D02*
G02X21143Y1379428I0J-1683D01*
G01D02*
X21277Y1379294D01*
G01D02*
G03X22699Y1378705I1422J1422D01*
G01D02*
X26610D01*
G01D02*
G03X28392Y1379443I0J2520D01*
G01D02*
X28796Y1379847D01*
G01D02*
G03X29499Y1381544I-1697J1697D01*
G01D02*
Y1389529D01*
G01X21099Y1377050D02*
G02X21956Y1377405I857J-857D01*
G01D02*
X26610D01*
G01D02*
G03X29312Y1378523I1J3821D01*
G01D02*
X29716Y1378927D01*
G01D02*
G03X30799Y1381544I-2617J2616D01*
G01D02*
Y1388616D01*
G01X29499Y1389529D02*
G03X29379Y1390133I-1577J1D01*
G01D02*
X29153Y1390678D01*
G01D02*
G03X28596Y1391050I-557J-231D01*
G01D02*
X28499D01*
G01X30799Y1388616D02*
G02X31566Y1389383I767J0D01*
G01D02*
X32333D01*
G01X19574Y1395663D02*
X19580Y1395669D01*
G01D02*
G02X20946Y1395103I0J-1932D01*
G01D02*
G03X22281Y1394550I1335J1335D01*
G01D02*
X23188D01*
G01D02*
X23201Y1394537D01*
G01D02*
X23988D01*
G01D02*
G03X24839Y1394889I0J1204D01*
G01D02*
X25197Y1395248D01*
G01D02*
X28998Y1399049D01*
G01D02*
X28999D01*
G01D02*
G03X30198Y1401947I-2899J2896D01*
G01D02*
X30199Y1401946D01*
G01D02*
Y1409050D01*
G01X31499Y1409170D02*
Y1401947D01*
G01D02*
G02X29918Y1398130I-5398J0D01*
G01D02*
X26118Y1394330D01*
G01D02*
X25759Y1393970D01*
G01D02*
G02X23988Y1393237I-1770J1771D01*
G01D02*
X23201D01*
G01D02*
X23188Y1393224D01*
G01D02*
G03X21833Y1392547I340J-2375D01*
G01D02*
X21702Y1392416D01*
G01D02*
G02X20051Y1391732I-1651J1651D01*
G01X30199Y1409050D02*
G03X29280Y1411269I-3138J0D01*
G01D02*
X28999Y1411550D01*
G01X32451Y1411468D02*
G03X31499Y1409170I2298J-2298D01*
G01X18864Y1419293D02*
G02X20387Y1418662I0J-2154D01*
G01D02*
G03X21864Y1418050I1477J1476D01*
G01D02*
X22999D01*
G01D02*
G03X25834Y1419225I-1J4010D01*
G01D02*
X26329Y1419719D01*
G01D02*
X29553Y1422943D01*
G01D02*
G03X30840Y1426050I-3107J3107D01*
G01D02*
Y1433727D01*
G01X19322Y1415350D02*
X19328Y1415356D01*
G01D02*
G03X20996Y1416047I0J2359D01*
G01D02*
G02X22693Y1416750I1697J-1697D01*
G01D02*
X22999D01*
G01D02*
Y1416751D01*
G01D02*
G03X26753Y1418305I1J5309D01*
G01D02*
X27248Y1418799D01*
G01D02*
X30473Y1422023D01*
G01D02*
G03X32140Y1426050I-4027J4026D01*
G01D02*
Y1429778D01*
G01X30840Y1433727D02*
G03X30499Y1434550I-1164J0D01*
G01X32140Y1429778D02*
G02X33206Y1432352I3640J0D01*
G01X19128Y1446846D02*
X19134Y1446852D01*
G01D02*
G03X20863Y1447568I0J2445D01*
G01D02*
G02X22273Y1448152I1410J-1410D01*
G01D02*
X23536D01*
G01D02*
G03X26210Y1449259I1J3781D01*
G01X18940Y1435035D02*
X18946Y1435041D01*
G01D02*
G02X20411Y1434434I0J-2072D01*
G01D02*
G03X21831Y1433846I1420J1421D01*
G01D02*
X25100D01*
G01D02*
G03X26200Y1434946I0J1100D01*
G01D02*
Y1436895D01*
G01D02*
G02X27752Y1440642I5299J0D01*
G01D02*
X29166Y1442056D01*
G01D02*
G03X30199Y1444550I-2494J2494D01*
G01D02*
Y1446050D01*
G01D02*
G03X29673Y1447320I-1796J0D01*
G01D02*
X28697Y1448296D01*
G01X19467Y1431098D02*
X19473Y1431104D01*
G01D02*
G03X21257Y1431843I0J2523D01*
G01D02*
G02X22954Y1432546I1697J-1697D01*
G01D02*
X25100D01*
G01D02*
G03X27500Y1434946I0J2400D01*
G01D02*
Y1436550D01*
G01D02*
G02X27507Y1436821I4831J11D01*
G01D02*
X27554Y1437697D01*
G01D02*
G02X28284Y1439334I2501J-134D01*
G01D02*
X30086Y1441136D01*
G01D02*
G03X31499Y1444550I-3415J3413D01*
G01D02*
Y1447012D01*
G01D02*
G02X32094Y1448448I2031J0D01*
G01X20630Y1465658D02*
G03X21736Y1465200I1106J1106D01*
G01D02*
X23998D01*
G01D02*
G03X25383Y1465775I-1J1958D01*
G01D02*
X25384Y1465776D01*
G01D02*
X25580Y1465971D01*
G01D02*
X30286Y1470677D01*
G01X20721Y1463520D02*
G02X21638Y1463900I917J-917D01*
G01D02*
X23999D01*
G01D02*
G03X26303Y1464855I-1J3259D01*
G01D02*
X26499Y1465050D01*
G01D02*
X31206Y1469757D01*
G01X19209Y1450783D02*
X19215Y1450789D01*
G01D02*
G02X20999Y1450050I0J-2523D01*
G01D02*
G03X22174Y1449469I1445J1443D01*
G01D02*
G03X22443Y1449452I263J2025D01*
G01D02*
X23536D01*
G01D02*
G03X25290Y1450178I0J2481D01*
G01D02*
X25667Y1450556D01*
G01D02*
X26329Y1451219D01*
G01D02*
X29471Y1454361D01*
G01D02*
G03X30999Y1458050I-3689J3689D01*
G01D02*
Y1461019D01*
G01D02*
G03X30977Y1461319I-2120J-5D01*
G01D02*
G03X30378Y1462518I-2099J-299D01*
G01X26210Y1449259D02*
X26587Y1449637D01*
G01D02*
X30391Y1453441D01*
G01D02*
G03X32299Y1458050I-4610J4608D01*
G01D02*
Y1461567D01*
G01D02*
G02X32499Y1462050I683J0D01*
G01D02*
X32575Y1462126D01*
G01D02*
G02X33915Y1462681I1340J-1340D01*
G01X19254Y1482279D02*
X19260Y1482285D01*
G01D02*
G02X20974Y1481575I0J-2424D01*
G01D02*
X21499Y1481050D01*
G01D02*
G03X21982Y1480850I483J483D01*
G01D02*
X24099D01*
G01D02*
G03X25653Y1481493I1J2197D01*
G01D02*
X25704Y1481545D01*
G01D02*
X26804Y1482645D01*
G01D02*
G03X27154Y1483489I-845J845D01*
G01D02*
Y1483490D01*
G01D02*
G02X28012Y1485564I2933J1D01*
G01D02*
X28676Y1486228D01*
G01D02*
X30793Y1488344D01*
G01D02*
G03X31499Y1490050I-1706J1705D01*
G01D02*
Y1495136D01*
G01X19186Y1478342D02*
X19192Y1478348D01*
G01D02*
G03X20966Y1479083I0J2509D01*
G01D02*
X21111Y1479228D01*
G01D02*
G02X21633Y1479520I778J-778D01*
G01D02*
G02X21887Y1479550I255J-1066D01*
G01D02*
X24099D01*
G01D02*
Y1479551D01*
G01D02*
G03X26578Y1480578I3J3497D01*
G01D02*
X26632Y1480634D01*
G01D02*
X27723Y1481725D01*
G01D02*
G03X28453Y1483487I-1762J1762D01*
G01D02*
Y1483490D01*
G01D02*
G02X28932Y1484644I1633J-1D01*
G01D02*
X31667Y1487379D01*
G01D02*
G03X32799Y1490112I-2733J2733D01*
G01D02*
Y1494550D01*
G01X30286Y1470677D02*
G03X31999Y1474810I-4134J4135D01*
G01D02*
Y1479636D01*
G01D02*
G03X30999Y1482050I-3414J0D01*
G01X31206Y1469757D02*
G03X33299Y1474811I-5055J5054D01*
G01D02*
Y1479050D01*
G01D02*
G02X34336Y1481555I3542J1D01*
G01D02*
X34465Y1481683D01*
G01X19381Y1498027D02*
X19387Y1498033D01*
G01D02*
G02X21270Y1497253I0J-2663D01*
G01D02*
G03X22967Y1496550I1697J1697D01*
G01D02*
X23031D01*
G01D02*
G03X24728Y1497253I0J2400D01*
G01D02*
X29920Y1502445D01*
G01D02*
G03X30999Y1505050I-2605J2605D01*
G01D02*
Y1509766D01*
G01D02*
G03X30115Y1511900I-3018J0D01*
G01X33512Y1512051D02*
G03X32299Y1509123I2928J-2928D01*
G01D02*
Y1505050D01*
G01D02*
G02X30838Y1501523I-4988J0D01*
G01D02*
X25648Y1496333D01*
G01D02*
G02X23031Y1495250I-2616J2617D01*
G01D02*
X22967D01*
G01D02*
G02X22916I-25J3700D01*
G01D02*
X22501D01*
G01D02*
G03X21049Y1494648I0J-2052D01*
G01D02*
X21000Y1494600D01*
G01D02*
G02X19783Y1494096I-1217J1217D01*
G01X31499Y1495136D02*
G03X30499Y1497550I-3414J0D01*
G01X32799Y1494550D02*
G02X34001Y1497452I4104J0D01*
G01D02*
X34099Y1497550D01*
G01X19440Y1509838D02*
X19446Y1509844D01*
G01D02*
G03X20689Y1510359I0J1758D01*
G01D02*
G02X22357Y1511050I1668J-1668D01*
G01D02*
X22999D01*
G01D02*
G03X26194Y1512377I2J4505D01*
G01X19183Y1513775D02*
X19189Y1513781D01*
G01D02*
G02X20985Y1513037I0J-2540D01*
G01D02*
X21255Y1512767D01*
G01D02*
G03X22262Y1512350I1007J1007D01*
G01D02*
X22999D01*
G01D02*
G03X25265Y1513288I1J3204D01*
G01D02*
X25292Y1513316D01*
G01D02*
X25740Y1513765D01*
G01D02*
G03X26480Y1515550I-1785J1786D01*
G01D02*
Y1518550D01*
G01D02*
G02X28475Y1523365I6810J-1D01*
G01D02*
X29508Y1524398D01*
G01D02*
G02X33499Y1526051I3991J-3991D01*
G01D02*
X35228D01*
G01D02*
G02X40024Y1524064I-1J-6785D01*
G01D02*
X40518Y1523571D01*
G01X26194Y1512377D02*
X26221Y1512405D01*
G01D02*
X26432Y1512616D01*
G01D02*
X26659Y1512842D01*
G01D02*
G03X27780Y1515550I-2708J2707D01*
G01D02*
Y1518549D01*
G01D02*
G02X29395Y1522445I5509J-1D01*
G01D02*
X30441Y1523491D01*
G01D02*
G02X33483Y1524751I3042J-3042D01*
G01D02*
X35227D01*
G01D02*
Y1524750D01*
G01D02*
G02X39105Y1523144I0J-5484D01*
G01D02*
X39599Y1522651D01*
G01D02*
X47077Y1515173D01*
G01X43759Y1514311D02*
X40008Y1518061D01*
G01D02*
X39334Y1518735D01*
G01D02*
G03X35499Y1520323I-3834J-3834D01*
G01D02*
X34499D01*
G01D02*
G02X32241Y1521259I1J3194D01*
G01D02*
X31999Y1521500D01*
G01X42839Y1513391D02*
X39089Y1517141D01*
G01D02*
X38414Y1517815D01*
G01D02*
G03X35499Y1519023I-2915J-2913D01*
G01D02*
X34499D01*
G01D02*
G03X32241Y1518087I1J-3194D01*
G01D02*
X31999Y1517846D01*
G01X20265Y1568006D02*
X20266D01*
G01D02*
G03X21322Y1567568I1057J1056D01*
G01D02*
X24999D01*
G01D02*
G03X26573Y1567937I-1J3544D01*
G01D02*
G03X26856Y1568094I-1576J3174D01*
G01D02*
G03X28012Y1569771I-1325J2150D01*
G01D02*
G03X27123Y1572205I-2481J473D01*
G01X20559Y1565808D02*
X20666Y1565915D01*
G01D02*
G02X21477Y1566251I811J-811D01*
G01D02*
G02X21655Y1566262I184J-1539D01*
G01D02*
X24999D01*
G01D02*
G03X27129Y1566818I0J4360D01*
G01D02*
G03X27499Y1567050I-2128J3805D01*
G01D02*
G03X29669Y1569455I-4131J5909D01*
G01D02*
G03X30520Y1572049I-6301J3504D01*
G01X20617Y1615274D02*
G03X21747Y1614806I1130J1130D01*
G01D02*
X23880D01*
G01D02*
G03X23958Y1614807I7J2501D01*
G01D02*
G03X25648Y1615538I-78J2500D01*
G01D02*
X28596Y1618486D01*
G01X20624Y1613056D02*
X20625D01*
G01D02*
G02X21710Y1613506I1086J-1085D01*
G01D02*
X23879D01*
G01D02*
G03X23997Y1613507I27J3801D01*
G01D02*
G03X26568Y1614618I-117J3800D01*
G01D02*
X26999Y1615049D01*
G01D02*
Y1615050D01*
G01D02*
X29315Y1617366D01*
G01D02*
X29378Y1617428D01*
G01D02*
G03X31499Y1622550I-5122J5121D01*
G01X20654Y1599293D02*
X20655D01*
G01D02*
G03X21723Y1598850I1069J1068D01*
G01D02*
X22999D01*
G01D02*
G03X27779Y1600830I0J6760D01*
G01D02*
X29499Y1602550D01*
G01D02*
G03X30079Y1603950I-1400J1400D01*
G01D02*
Y1611550D01*
G01D02*
G03X29518Y1612906I-1917J1D01*
G01D02*
X28899Y1613524D01*
G01X18863Y1596458D02*
G03X20944Y1597320I0J2943D01*
G01D02*
G02X21499Y1597550I555J-555D01*
G01D02*
X22999D01*
G01D02*
G03X24830Y1597760I3J8061D01*
G01D02*
G03X28699Y1599910I-1830J7850D01*
G01D02*
X30419Y1601630D01*
G01D02*
G03X31379Y1603949I-2320J2319D01*
G01D02*
Y1611568D01*
G01D02*
G02X32111Y1613336I2501J0D01*
G01D02*
X32299Y1613524D01*
G01X19367Y1631885D02*
X19373Y1631891D01*
G01D02*
G02X20800Y1631300I0J-2018D01*
G01D02*
X21086Y1631014D01*
G01D02*
G03X22160Y1630569I1074J1074D01*
G01D02*
X23821D01*
G01D02*
G03X25482Y1631373I-324J2786D01*
G01D02*
X25829Y1631719D01*
G01D02*
X29079Y1634969D01*
G01D02*
X29108Y1634997D01*
G01D02*
G03X30554Y1638044I-3553J3553D01*
G01D02*
G03X30578Y1638519I-4697J475D01*
G01D02*
Y1638550D01*
G01D02*
X30579Y1638549D01*
G01D02*
Y1642701D01*
G01X18998Y1627948D02*
X19004Y1627954D01*
G01D02*
G03X20539Y1628590I0J2171D01*
G01D02*
G02X22092Y1629273I1655J-1656D01*
G01D02*
X22174Y1629277D01*
G01D02*
G02X22200Y1629278I103J-2345D01*
G01D02*
X23972D01*
G01D02*
G03X26401Y1630453I-474J4078D01*
G01D02*
X26748Y1630799D01*
G01D02*
X29999Y1634050D01*
G01D02*
X30026Y1634078D01*
G01D02*
G03X31879Y1638550I-4471J4472D01*
G01D02*
Y1642282D01*
G01X28596Y1618486D02*
G03X30199Y1622356I-3870J3870D01*
G01D02*
Y1628360D01*
G01D02*
G03X29499Y1630050I-2390J0D01*
G01X31499Y1622550D02*
Y1626050D01*
G01D02*
G02X31698Y1626994I2335J1D01*
G01D02*
G02X32183Y1627701I2135J-945D01*
G01D02*
X32663Y1628181D01*
G01X30579Y1642701D02*
G03X29626Y1645002I-3254J0D01*
G01X31879Y1642282D02*
G02X33026Y1645051I3916J0D01*
G01X20740Y1646675D02*
G03X21641Y1646302I901J901D01*
G01D02*
X23999D01*
G01D02*
G03X25465Y1646674I-3J3086D01*
G01D02*
Y1646673D01*
G01D02*
G03X26181Y1647207I-1468J2715D01*
G01D02*
X27011Y1648037D01*
G01D02*
X27200Y1648225D01*
G01D02*
Y1648227D01*
G01D02*
X28511Y1649538D01*
G01D02*
G03X29699Y1652406I-2868J2868D01*
G01D02*
Y1658386D01*
G01D02*
G03X28600Y1661039I-3752J0D01*
G01X20626Y1644553D02*
G02X21710Y1645002I1084J-1084D01*
G01D02*
X23999D01*
G01D02*
G03X27101Y1646287I0J4387D01*
G01D02*
X28500Y1647686D01*
G01D02*
Y1647687D01*
G01D02*
X28620Y1647807D01*
G01D02*
X29181Y1648367D01*
G01D02*
Y1648368D01*
G01D02*
X29431Y1648618D01*
G01D02*
G03X30999Y1652405I-3789J3787D01*
G01D02*
Y1658713D01*
G01D02*
G02X31999Y1661127I3414J0D01*
G01X19044Y1659444D02*
X19050Y1659450D01*
G01D02*
G03X21353Y1660404I0J3257D01*
G01X20590Y1662537D02*
G03X21766Y1662050I1176J1176D01*
G01D02*
X22500D01*
G01D02*
G03X25488Y1663287I1J4225D01*
G01D02*
X29300Y1667099D01*
G01D02*
X29546Y1667344D01*
G01D02*
G03X29876Y1667963I-857J854D01*
G01D02*
G03Y1667965I-1210J1D01*
G01D02*
G03X29896Y1668103I-1185J242D01*
G01D02*
G03X29900Y1668200I-1206J98D01*
G01D02*
G03X29546Y1669053I-1207J-1D01*
G01D02*
X29100Y1669500D01*
G01X21353Y1660404D02*
G02X22188Y1660750I835J-835D01*
G01D02*
X22500D01*
G01D02*
Y1660751D01*
G01D02*
G03X26410Y1662369I3J5525D01*
G01D02*
X26523Y1662484D01*
G01D02*
X30819Y1666780D01*
G01D02*
G03X31200Y1667700I-920J920D01*
G01D02*
Y1667702D01*
G01D02*
G02X31703Y1668916I1717J0D01*
G01D02*
X32494Y1669706D01*
G01X59999Y243365D02*
Y146237D01*
G01D02*
G03X61079Y143630I3687J0D01*
G01D02*
X82041Y122668D01*
G01X59999Y346605D02*
Y246263D01*
G01D02*
G02X59750Y246014I-249J0D01*
G01D02*
X59749D01*
G01D02*
G03X59500Y245765I0J-249D01*
G01D02*
Y243863D01*
G01D02*
G03X59749Y243614I249J0D01*
G01D02*
X59750D01*
G01D02*
G02X59999Y243365I0J-249D01*
G01X60099Y349150D02*
G02X61299Y346253I-2897J-2897D01*
G01X59429Y347981D02*
G02X59999Y346605I-1376J-1376D01*
G01X40150Y451250D02*
X49599Y460699D01*
G01X50519Y459780D02*
X41069Y450330D01*
G01D02*
Y450331D01*
G01X49599Y460699D02*
X49600D01*
G01D02*
G02X53224Y462200I3623J-3623D01*
G01D02*
X174593D01*
G01X174594Y460900D02*
X53223D01*
G01D02*
G03X50519Y459780I0J-3824D01*
G01X44249Y463449D02*
X44250D01*
G01D02*
G02X50409Y466000I6158J-6158D01*
G01D02*
X172225D01*
G01X172226Y464700D02*
X50408D01*
G01D02*
G03X45169Y462530I0J-7409D01*
G01D02*
X40169Y457530D01*
G01D02*
Y457531D01*
G01X42351Y497797D02*
X74101Y529547D01*
G01X43571Y497178D02*
X75021Y528627D01*
G01X64279Y527169D02*
X42529Y505419D01*
G01D02*
G02X40318Y504503I-2211J2211D01*
G01X65198Y526249D02*
X43699Y504750D01*
G01D02*
G02X39964Y503203I-3735J3735D01*
G01X84499Y580050D02*
X40409Y520331D01*
G01D02*
X40398Y520330D01*
G01D02*
X40108Y520045D01*
G01X50213Y614806D02*
G03X60803Y619194I-2J14978D01*
G01D02*
X61078Y619469D01*
G01D02*
X61079D01*
G01D02*
X66872Y625262D01*
G01X50212Y613506D02*
G03X61723Y618274I0J16279D01*
G01X64079Y629470D02*
G02X47689Y622680I-16391J16389D01*
G01Y621380D02*
G03X64999Y628550I0J24480D01*
G01X54748Y630554D02*
G03X60579Y632970I0J8245D01*
G01D02*
G03X62199Y636879I-3907J3910D01*
G01X54749Y629254D02*
G03X61499Y632050I0J9546D01*
G01X58199Y670640D02*
Y644379D01*
G01D02*
G02X56579Y640470I-5527J1D01*
G01D02*
G02X51650Y638427I-4931J4929D01*
G01X59499Y670641D02*
Y644378D01*
G01D02*
G02X57499Y639550I-6828J0D01*
G01D02*
G02X51649Y637127I-5850J5850D01*
G01X50499Y646302D02*
G03X54198Y650001I0J3699D01*
G01D02*
Y653793D01*
G01D02*
X54199Y653792D01*
G01D02*
Y674794D01*
G01X50499Y645002D02*
G03X55498Y650001I0J4999D01*
G01D02*
Y653793D01*
G01D02*
X55499D01*
G01D02*
Y674795D01*
G01X49699Y678813D02*
Y658879D01*
G01D02*
G02X48079Y654970I-5527J1D01*
G01D02*
G02X46584Y654350I-1495J1493D01*
G01X50999Y678812D02*
Y658878D01*
G01D02*
G02X48999Y654050I-6828J0D01*
G01D02*
G02X46585Y653050I-2414J2414D01*
G01X40199Y662050D02*
G03X44699Y666550I0J4500D01*
G01X40199Y660750D02*
G03X45999Y666550I0J5800D01*
G01X130499Y746550D02*
X60749Y676800D01*
G01D02*
X60750Y676799D01*
G01D02*
G03X58199Y670640I6158J-6158D01*
G01X61669Y675880D02*
G03X59499Y670641I5239J-5239D01*
G01X54199Y674794D02*
G02X57730Y683319I12055J1D01*
G01D02*
X57729D01*
G01D02*
X117329Y742919D01*
G01X55499Y674795D02*
G02X58649Y682400I10755J0D01*
G01D02*
X118248Y741999D01*
G01X114499Y747150D02*
X52199Y684850D01*
G01D02*
X52200Y684849D01*
G01D02*
G03X49699Y678813I6037J-6038D01*
G01X115419Y746230D02*
X53119Y683930D01*
G01D02*
G03X50999Y678812I5118J-5118D01*
G01X44699Y666550D02*
Y678455D01*
G01D02*
G02X48330Y687219I12396J-2D01*
G01X45999Y666550D02*
Y678454D01*
G01D02*
G02X49249Y686300I11096J0D01*
G01D02*
X103861Y740912D01*
G01X48330Y687219D02*
X48329Y687220D01*
G01D02*
X102941Y741832D01*
G01X98699Y753750D02*
X42498Y697549D01*
G01D02*
X42499D01*
G01D02*
G03X40496Y695052I10381J-10379D01*
G01X99618Y752830D02*
X43418Y696630D01*
G01D02*
G03X41592Y694354I9461J-9461D01*
G01X61816Y872182D02*
G02X59200Y878499I6319J6317D01*
G01X62736Y873102D02*
G02X60500Y878500I5398J5398D01*
G01X59200Y878499D02*
Y1325112D01*
G01X60500Y878500D02*
Y1325111D01*
G01X59200Y1325112D02*
G02X62331Y1332669I10689J-1D01*
G01X60500Y1325111D02*
G02X63250Y1331750I9389J0D01*
G01X52004Y1369416D02*
G02X52262Y1369158I0J-258D01*
G01D02*
G03X52520Y1368900I258J0D01*
G01D02*
X54404D01*
G01D02*
G03X54662Y1369158I0J258D01*
G01D02*
G02X54920Y1369416I258J0D01*
G01D02*
X56804D01*
G01D02*
G02X57062Y1369158I0J-258D01*
G01D02*
G03X57320Y1368900I258J0D01*
G01D02*
X59204D01*
G01D02*
G03X59462Y1369158I0J258D01*
G01D02*
G02X59720Y1369416I258J0D01*
G01D02*
X63600D01*
G01X50499Y1491550D02*
G03X53327Y1484721I9657J-1D01*
G01D02*
X53499Y1484550D01*
G01D02*
X99911Y1438138D01*
G01X49199Y1491550D02*
G03X52408Y1483803I10956J0D01*
G01D02*
X52409Y1483802D01*
G01D02*
X52635Y1483575D01*
G01D02*
X55829Y1480380D01*
G01D02*
X98991Y1437218D01*
G01X101376Y1430972D02*
X51648Y1480700D01*
G01D02*
X51649Y1480701D01*
G01D02*
X49400Y1482950D01*
G01D02*
X49130Y1483221D01*
G01D02*
X49126Y1483225D01*
G01D02*
G02X47173Y1486038I6830J6827D01*
G01D02*
X47172Y1486041D01*
G01D02*
G02X46302Y1489823I8784J4012D01*
G01D02*
X46301Y1489847D01*
G01D02*
G02X46299Y1490051I8568J186D01*
G01D02*
Y1508176D01*
G01X99979Y1430531D02*
X48479Y1482031D01*
G01D02*
X48209Y1482302D01*
G01D02*
G02X44999Y1490050I7748J7749D01*
G01D02*
Y1508176D01*
G01X48151Y1515934D02*
G02X50500Y1510053I-6191J-5883D01*
G01D02*
X50499D01*
G01D02*
Y1491550D01*
G01X47078Y1515171D02*
G02X49199Y1510052I-5115J-5118D01*
G01D02*
G02Y1510050I-7245J-1D01*
G01D02*
Y1491550D01*
G01X46299Y1508176D02*
G03X43759Y1514311I-8675J2D01*
G01X44999Y1508176D02*
G03X42839Y1513391I-7375J0D01*
G01X40518Y1523571D02*
X48146Y1515944D01*
G01D02*
X48151Y1515934D01*
G01X47077Y1515173D02*
X47078Y1515171D01*
G01X63249Y143300D02*
X82956Y123593D01*
G01X82041Y122668D02*
G03X86671Y120750I4630J4630D01*
G01X61299Y346253D02*
Y146238D01*
G01D02*
G03X61998Y144550I2387J0D01*
G01D02*
X62925Y143623D01*
G01D02*
X63249Y143300D01*
G01X66376Y224013D02*
X92927Y197462D01*
G01X65456Y223093D02*
X92007Y196542D01*
G01X64999Y350166D02*
Y227335D01*
G01D02*
G03X66376Y224013I4699J1D01*
G01X63699Y350166D02*
Y227334D01*
G01D02*
G03X65456Y223093I5999J1D01*
G01X69949Y289500D02*
X123899Y235550D01*
G01X69029Y288580D02*
X122976Y234634D01*
G01X73299Y292050D02*
X126249Y239100D01*
G01X72470Y291040D02*
X125479Y238031D01*
G01X68699Y353150D02*
Y292518D01*
G01D02*
G03X69949Y289500I4268J0D01*
G01X67399Y353150D02*
Y292519D01*
G01D02*
G03X69030Y288581I5568J-1D01*
G01D02*
X69029Y288580D01*
G01X72399Y358665D02*
Y294223D01*
G01D02*
G03X73299Y292050I3073J0D01*
G01X71099Y358665D02*
Y294350D01*
G01D02*
G03X72470Y291040I4681J0D01*
G01X77512Y306875D02*
X126917Y257469D01*
G01X74799Y310638D02*
G03X76842Y305706I6975J0D01*
G01D02*
X125998Y256550D01*
G01X80166Y307617D02*
X119554Y268229D01*
G01X76099Y368106D02*
Y310286D01*
G01D02*
G03X77512Y306875I4824J0D01*
G01X74799Y368105D02*
Y310638D01*
G01X79799Y370217D02*
Y311644D01*
G01D02*
G03X81086Y308537I4394J0D01*
G01D02*
X127956Y261667D01*
G01X78499Y375394D02*
Y311643D01*
G01D02*
G03X80166Y307617I5695J0D01*
G01X63242Y354408D02*
G02X64999Y350166I-4242J-4242D01*
G01X62322Y353488D02*
G02X63699Y350166I-3322J-3323D01*
G01X65597Y360252D02*
X65871Y359979D01*
G01D02*
G02X68699Y353150I-6829J-6828D01*
G01X64952Y359058D02*
G02X67400Y353150I-5909J-5910D01*
G01D02*
X67399D01*
G01X70262Y363827D02*
G02X72399Y358665I-5163J-5161D01*
G01X69342Y362907D02*
G02X71099Y358665I-4242J-4242D01*
G01X75176Y370374D02*
G02X76099Y368106I-2324J-2267D01*
G01X74229Y369481D02*
G02X74799Y368105I-1376J-1376D01*
G01X74948Y370601D02*
X74949D01*
G01D02*
X75149Y370401D01*
G01D02*
G02X75176Y370374I-2282J-2309D01*
G01X78068Y379220D02*
G02X79799Y375041I-4179J-4179D01*
G01D02*
Y373117D01*
G01D02*
G03X80049Y372867I250J0D01*
G01D02*
X80050D01*
G01D02*
G02X80300Y372617I0J-250D01*
G01D02*
Y370717D01*
G01D02*
G02X80050Y370467I-250J0D01*
G01D02*
X80049D01*
G01D02*
G03X79799Y370217I0J-250D01*
G01X77399Y378050D02*
G02X78499Y375394I-2656J-2656D01*
G01X67499Y433704D02*
G02X71228Y432160I1J-5273D01*
G01D02*
X71368Y432019D01*
G01D02*
X73918Y429469D01*
G01D02*
X73944Y429442D01*
G01D02*
G03X76099Y428550I2154J2155D01*
G01D02*
X81281D01*
G01D02*
G03X83145Y429322I0J2636D01*
G01X67583Y432404D02*
G02X70248Y431300I0J-3769D01*
G01D02*
X72698Y428850D01*
G01D02*
X73024Y428523D01*
G01D02*
G03X76099Y427250I3074J3075D01*
G01D02*
X80730D01*
G01D02*
G03X84455Y428793I0J5268D01*
G01X74101Y529547D02*
X834716Y1457033D01*
G01X75021Y528627D02*
X75106Y528722D01*
G01D02*
X835640Y1456108D01*
G01X817202Y1455998D02*
X65811Y528896D01*
G01D02*
X64279Y527169D01*
G01X818212Y1455180D02*
X65989Y527050D01*
G01D02*
X65252Y526306D01*
G01D02*
X65198Y526249D01*
G01X61723Y618274D02*
X67792Y624342D01*
G01X62199Y636879D02*
Y668554D01*
G01X61499Y632050D02*
G03X63499Y636878I-4828J4828D01*
G01D02*
Y668555D01*
G01X66872Y625262D02*
G03X70698Y634500I-9239J9238D01*
G01D02*
X70699Y634499D01*
G01D02*
Y666977D01*
G01X67792Y624342D02*
G03X71999Y634500I-10158J10157D01*
G01D02*
Y666977D01*
G01X66199Y667157D02*
Y634585D01*
G01D02*
X66198Y634586D01*
G01D02*
G02X64079Y629470I-7235J0D01*
G01X64999Y628550D02*
G03X67499Y634586I-6036J6036D01*
G01D02*
Y667156D01*
G01X76999Y664550D02*
G03X77471Y665690I-1140J1140D01*
G01X80499Y664550D02*
X80206D01*
G01D02*
G02X78999Y665050I0J1707D01*
G01D02*
G02X78768Y665608I558J558D01*
G01D02*
Y667799D01*
G01X62199Y668554D02*
G02X64482Y674066I7794J1D01*
G01D02*
X64481Y674067D01*
G01D02*
X134581Y744167D01*
G01X63499Y668555D02*
G02X65401Y673147I6494J0D01*
G01D02*
X135501Y743247D01*
G01X131419Y745630D02*
X61669Y675880D01*
G01X70699Y666977D02*
G02X71980Y670070I4373J1D01*
G01D02*
X141679Y739769D01*
G01X71999Y666977D02*
G02X72899Y669150I3073J0D01*
G01D02*
X142599Y738850D01*
G01X138849Y743200D02*
X68598Y672949D01*
G01D02*
G03X66199Y667157I5794J-5793D01*
G01X67499Y667156D02*
G02X69518Y672030I6893J0D01*
G01D02*
X139768Y742280D01*
G01X77471Y665690D02*
Y667851D01*
G01D02*
G02X78379Y669930I3108J-120D01*
G01D02*
X78399Y669950D01*
G01D02*
X81498Y673050D01*
G01D02*
G02X83915Y674050I2416J-2418D01*
G01X78768Y667799D02*
G02X79299Y669010I1809J-71D01*
G01D02*
X82418Y672130D01*
G01X92891Y841109D02*
X62060Y871940D01*
G01X93169Y842669D02*
X62736Y873102D01*
G01X62060Y871940D02*
X62059Y871939D01*
G01D02*
X61816Y872182D01*
G01X62331Y1332669D02*
X62330D01*
G01D02*
X83580Y1353919D01*
G01X63250Y1331750D02*
X84500Y1353000D01*
G01X80279Y1370716D02*
G03X83499Y1372050I-1J4555D01*
G01X63600Y1369416D02*
G02X63808Y1369208I0J-208D01*
G01D02*
G03X64016Y1369000I208J0D01*
G01D02*
X66000D01*
G01D02*
G03X66208Y1369208I0J208D01*
G01D02*
G02X66416Y1369416I208J0D01*
G01D02*
X80278D01*
G01D02*
G03X84419Y1371130I2J5856D01*
G01X82956Y123593D02*
G03X83157Y123402I3831J3831D01*
G01D02*
G03X86672Y122050I3516J3895D01*
G01D02*
X94970D01*
G01D02*
G03X98432Y123484I0J4896D01*
G01D02*
X101864Y126915D01*
G01D02*
G02X105814Y128550I3951J-3955D01*
G01X86671Y120750D02*
X94970D01*
G01D02*
G03X99352Y122564I1J6197D01*
G01D02*
X102668Y125880D01*
G01D02*
X102782Y125993D01*
G01D02*
G02X105815Y127250I3034J-3033D01*
G01X101299Y177250D02*
Y134996D01*
G01D02*
G02X99499Y130650I-6146J0D01*
G01D02*
G02X92015Y127550I-7484J7484D01*
G01D02*
X88423D01*
G01D02*
G03X88146Y127534I4J-2472D01*
G01D02*
G03X87835Y127478I284J-2469D01*
G01D02*
G03X86671Y126822I593J-2413D01*
G01D02*
X86599Y126750D01*
G01X99999Y177250D02*
Y134995D01*
G01D02*
X99998Y134996D01*
G01D02*
G02X98579Y131570I-4845J0D01*
G01D02*
G02X92014Y128850I-6565J6563D01*
G01D02*
X87016D01*
G01D02*
G02X86099Y129767I0J917D01*
G01D02*
G02X86899Y130567I800J0D01*
G01X92927Y197462D02*
G02X101299Y177250I-20212J-20212D01*
G01X92007Y196542D02*
G02X99999Y177250I-19292J-19293D01*
G01X83145Y429322D02*
X86336Y432513D01*
G01D02*
G02X89047Y433636I2711J-2711D01*
G01X84455Y428793D02*
X87355Y431693D01*
G01D02*
G02X88907Y432336I1552J-1552D01*
G01D02*
X276099D01*
G01X89047Y433636D02*
X276099D01*
G01X125168Y649909D02*
X83417Y580774D01*
G01X125902Y648609D02*
X84499Y580050D01*
G01X82572Y635624D02*
G03X84199Y639551I-3926J3927D01*
G01D02*
Y641514D01*
G01D02*
G02X87080Y648470I9836J1D01*
G01X83492Y634704D02*
G03X85499Y639550I-4847J4846D01*
G01D02*
Y641514D01*
G01D02*
G02X87999Y647550I8536J0D01*
G01X87080Y648470D02*
X87079D01*
G01D02*
X147079Y708470D01*
G01X87999Y647550D02*
X147999Y707550D01*
G01X83915Y674050D02*
X90456D01*
G01D02*
G03X92112Y674736I0J2342D01*
G01D02*
X129892Y712516D01*
G01X82418Y672130D02*
G02X83915Y672750I1497J-1497D01*
G01D02*
X90457D01*
G01D02*
G03X93031Y673816I-1J3642D01*
G01D02*
X147032Y727817D01*
G01X102941Y741832D02*
G03X104848Y746436I-4604J4604D01*
G01X101149Y783212D02*
Y759665D01*
G01D02*
G02X98699Y753750I-8365J0D01*
G01X102449Y926132D02*
Y759665D01*
G01D02*
G02X99618Y752830I-9665J-1D01*
G01X93330Y753669D02*
G03X94800Y757218I-3549J3549D01*
G01D02*
Y836500D01*
G01X94249Y752749D02*
Y752750D01*
G01D02*
G03X96100Y757219I-4468J4468D01*
G01D02*
Y836499D01*
G01X101149Y795104D02*
Y786060D01*
G01D02*
G02X100925Y785836I-224J0D01*
G01D02*
X100924D01*
G01D02*
G03X100700Y785612I0J-224D01*
G01D02*
Y783660D01*
G01D02*
G03X100924Y783436I224J0D01*
G01D02*
X100925D01*
G01D02*
G02X101149Y783212I0J-224D01*
G01Y909749D02*
Y802752D01*
G01D02*
G02X100925Y802528I-224J0D01*
G01D02*
X100924D01*
G01D02*
G03X100700Y802304I0J-224D01*
G01D02*
Y800352D01*
G01D02*
G03X100924Y800128I224J0D01*
G01D02*
X100925D01*
G01D02*
G02X101149Y799904I0J-224D01*
G01D02*
Y797952D01*
G01D02*
G02X100925Y797728I-224J0D01*
G01D02*
X100924D01*
G01D02*
G03X100700Y797504I0J-224D01*
G01D02*
Y795552D01*
G01D02*
G03X100924Y795328I224J0D01*
G01D02*
X100925D01*
G01D02*
G02X101149Y795104I0J-224D01*
G01X94800Y836500D02*
G03X92891Y841109I-6518J0D01*
G01X96100Y836499D02*
G03X93811Y842029I-7819J2D01*
G01D02*
X93170Y842670D01*
G01D02*
X93169Y842669D01*
G01X101149Y926132D02*
Y917497D01*
G01D02*
G02X100875Y917223I-274J0D01*
G01D02*
X100874D01*
G01D02*
G03X100600Y916949I0J-274D01*
G01D02*
Y915097D01*
G01D02*
G03X100874Y914823I274J0D01*
G01D02*
X100875D01*
G01D02*
G02X101149Y914549I0J-274D01*
G01D02*
Y912697D01*
G01D02*
G02X100875Y912423I-274J0D01*
G01D02*
X100874D01*
G01D02*
G03X100600Y912149I0J-274D01*
G01D02*
Y910297D01*
G01D02*
G03X100874Y910023I274J0D01*
G01D02*
X100875D01*
G01D02*
G02X101149Y909749I0J-274D01*
G01X86399Y937050D02*
G02Y938350I650J650D01*
G01D02*
G02X87058Y938623I659J-659D01*
G01D02*
X89262D01*
G01D02*
G02X91249Y937800I0J-2810D01*
G01D02*
X99899Y929150D01*
G01D02*
G02X101149Y926132I-3018J-3018D01*
G01X85999Y940429D02*
G03X87221Y939923I1222J1222D01*
G01D02*
X89262D01*
G01D02*
G02X92169Y938719I1J-4110D01*
G01D02*
X100818Y930070D01*
G01D02*
G02X102449Y926132I-3937J-3937D01*
G01X117919Y1037581D02*
X100129Y1055370D01*
G01D02*
X100130Y1055371D01*
G01D02*
G02X97479Y1061769I6399J6400D01*
G01D02*
Y1329741D01*
G01X118469Y1038869D02*
X101049Y1056290D01*
G01D02*
G02X98779Y1061770I5480J5480D01*
G01D02*
Y1329741D01*
G01X93779Y1323861D02*
Y1059500D01*
G01D02*
G03X96027Y1054073I7675J0D01*
G01D02*
X112901Y1037199D01*
G01X95079Y1342443D02*
Y1059020D01*
G01D02*
G03X96607Y1055331I5217J0D01*
G01D02*
X114360Y1037578D01*
G01X97479Y1329741D02*
G02X98630Y1332520I3929J1D01*
G01D02*
X100679Y1334569D01*
G01D02*
G02X103772Y1335850I3093J-3093D01*
G01X98779Y1329741D02*
G02X99549Y1331600I2629J0D01*
G01D02*
X101799Y1333850D01*
G01D02*
G02X103489Y1334550I1690J-1690D01*
G01X93079Y1344130D02*
G02X93779Y1342442I-1686J-1688D01*
G01D02*
Y1331745D01*
G01D02*
G02X93439Y1331405I-340J0D01*
G01D02*
G03X93099Y1331065I0J-340D01*
G01D02*
Y1329345D01*
G01D02*
G03X93439Y1329005I340J0D01*
G01D02*
G02X93779Y1328665I0J-340D01*
G01D02*
Y1326741D01*
G01D02*
G02X93539Y1326501I-240J0D01*
G01D02*
G03X93299Y1326261I0J-240D01*
G01D02*
Y1324341D01*
G01D02*
G03X93539Y1324101I240J0D01*
G01D02*
G02X93779Y1323861I0J-240D01*
G01X93999Y1345050D02*
G02X95079Y1342443I-2607J-2607D01*
G01X93638Y1362836D02*
X93644Y1362842D01*
G01D02*
X96384D01*
G01D02*
G02X99496Y1361553I0J-4401D01*
G01D02*
G03X101193Y1360850I1697J1697D01*
G01D02*
X111309D01*
G01X96745Y1361536D02*
G02X98329Y1360880I0J-2240D01*
G01D02*
X98576Y1360633D01*
G01D02*
G03X101193Y1359550I2616J2617D01*
G01D02*
X110005D01*
G01X86890Y1342860D02*
G02X90246Y1344250I3356J-3356D01*
G01D02*
X92791D01*
G01D02*
G02X93079Y1344130I0J-406D01*
G01X86890Y1346635D02*
G03X89509Y1345550I2619J2619D01*
G01D02*
X92792D01*
G01D02*
G02X93999Y1345050I0J-1707D01*
G01X83580Y1353919D02*
X83581D01*
G01D02*
G02X89327Y1356300I5748J-5747D01*
G01D02*
X94494D01*
G01D02*
G02X97130Y1355208I0J-3728D01*
G01D02*
X97211Y1355129D01*
G01D02*
G02X98299Y1352500I-2624J-2626D01*
G01D02*
X98300D01*
G01D02*
Y1349190D01*
G01D02*
G03X99000Y1347500I2390J0D01*
G01D02*
G03X101696I1348J1348D01*
G01D02*
X102350Y1348154D01*
G01X84500Y1353000D02*
G02X89328Y1355000I4828J-4828D01*
G01D02*
X94486D01*
G01D02*
G02X96216Y1354283I0J-2445D01*
G01D02*
X96294Y1354206D01*
G01D02*
G02X97000Y1352500I-1706J-1705D01*
G01D02*
Y1349190D01*
G01D02*
G03X98080Y1346580I3691J-1D01*
G01D02*
G03X100821Y1345675I2269J2268D01*
G01D02*
G02X101350Y1345500I91J-612D01*
G01D02*
X102350Y1344500D01*
G01X83499Y1372050D02*
X92585Y1381136D01*
G01D02*
G02X95999Y1382550I3414J-3414D01*
G01D02*
X100378D01*
G01D02*
G02X103999Y1381050I0J-5121D01*
G01X104200Y1375500D02*
G02X100984Y1374168I-3216J3216D01*
G01D02*
X99235D01*
G01D02*
G03X97229Y1373337I0J-2837D01*
G01X84419Y1371130D02*
X93505Y1380216D01*
G01D02*
G02X95998Y1381250I2495J-2493D01*
G01D02*
X100377D01*
G01D02*
G02X103079Y1380130I0J-3820D01*
G01D02*
G02X103623Y1378944I-1331J-1328D01*
G01X103622Y1377244D02*
G02X103280Y1376420I-1164J0D01*
G01D02*
G02X100985Y1375468I-2297J2295D01*
G01D02*
X98019D01*
G01D02*
G02X97700Y1375600I0J451D01*
G01D02*
G02X97000Y1377290I1690J1690D01*
G01D02*
Y1377600D01*
G01X99911Y1438138D02*
Y1438137D01*
G01D02*
X100550Y1437497D01*
G01D02*
G03X104044Y1436050I3494J3496D01*
G01X98991Y1437218D02*
X99630Y1436578D01*
G01D02*
G03X104045Y1434750I4414J4415D01*
G01X106498Y1428849D02*
G02X101376Y1430972I2J7245D01*
G01X106369Y1427550D02*
G02X100456Y1430052I130J8545D01*
G01D02*
X99978Y1430530D01*
G01D02*
X99979Y1430531D01*
G01X107541Y1686893D02*
X102641Y1691793D01*
G01D02*
G02X100949Y1695878I4087J4086D01*
G01D02*
Y1737453D01*
G01X103561Y1692712D02*
G02X102249Y1695879I3167J3167D01*
G01D02*
Y1737812D01*
G01X97249Y1725668D02*
Y1694463D01*
G01D02*
G03X99025Y1690175I6063J-1D01*
G01D02*
X103224Y1685976D01*
G01D02*
G02X103999Y1684106I-1868J-1870D01*
G01X98549Y1742250D02*
Y1694463D01*
G01D02*
G03X99944Y1691095I4763J0D01*
G01D02*
X104144Y1686895D01*
G01X100949Y1737453D02*
G02X102221Y1740524I4343J0D01*
G01D02*
G02X105883Y1741850I3663J-4396D01*
G01X102249Y1737812D02*
G02X102924Y1739442I2305J0D01*
G01D02*
G02X105599Y1740550I2675J-2675D01*
G01X96154Y1744892D02*
G02X97249Y1742250I-2642J-2643D01*
G01D02*
Y1738218D01*
G01D02*
G02X96974Y1737943I-275J0D01*
G01D02*
G03X96699Y1737668I0J-275D01*
G01D02*
Y1735818D01*
G01D02*
G03X96974Y1735543I275J0D01*
G01D02*
G02X97249Y1735268I0J-275D01*
G01D02*
Y1733418D01*
G01D02*
G02X96974Y1733143I-275J0D01*
G01D02*
G03X96699Y1732868I0J-275D01*
G01D02*
Y1731018D01*
G01D02*
G03X96974Y1730743I275J0D01*
G01D02*
G02X97249Y1730468I0J-275D01*
G01D02*
Y1728618D01*
G01D02*
G02X96974Y1728343I-275J0D01*
G01D02*
G03X96699Y1728068I0J-275D01*
G01D02*
Y1726218D01*
G01D02*
G03X96974Y1725943I275J0D01*
G01D02*
G02X97249Y1725668I0J-275D01*
G01X97074Y1745812D02*
G02X98548Y1742250I-3563J-3560D01*
G01D02*
X98549D01*
G01X85194Y1748848D02*
G02X86889Y1749550I1695J-1695D01*
G01D02*
X89999D01*
G01D02*
G02X92556Y1748491I0J-3616D01*
G01D02*
X95198Y1745849D01*
G01D02*
X96154Y1744892D01*
G01X85341Y1752245D02*
X86056Y1751530D01*
G01D02*
G03X87258Y1750892I1641J1641D01*
G01D02*
G03X87699Y1750850I440J2283D01*
G01D02*
X89998D01*
G01D02*
G02X90700Y1750800I3J-4917D01*
G01D02*
G02X93476Y1749411I-699J-4866D01*
G01D02*
X94468Y1748419D01*
G01D02*
X94467Y1748418D01*
G01D02*
X97074Y1745812D01*
G01X105814Y128550D02*
X114366D01*
G01D02*
G03X114622Y128601I0J668D01*
G01D02*
X114754Y128656D01*
G01D02*
G03X115204Y128956I-530J1283D01*
G01D02*
X115576Y129328D01*
G01D02*
G03X115876Y130050I-721J723D01*
G01X105815Y127250D02*
X114599D01*
G01D02*
G02X115876Y125973I0J-1277D01*
G01X123899Y235550D02*
X124021Y235427D01*
G01D02*
G03X129399Y233200I5377J5378D01*
G01X122976Y234634D02*
X123099Y234509D01*
G01D02*
G03X129399Y231901I6297J6297D01*
G01X125499Y250050D02*
X124399D01*
G01D02*
G03X123204Y249555I0J-1690D01*
G01D02*
X122799Y249150D01*
G01X125499Y251350D02*
X123083D01*
G01D02*
G02X122598Y251551I0J686D01*
G01D02*
G02X122397Y252036I485J485D01*
G01D02*
Y252688D01*
G01X119554Y268229D02*
X127415Y260367D01*
G01X117329Y742919D02*
G03X119899Y749124I-6205J6205D01*
G01D02*
Y1032800D01*
G01X118248Y741999D02*
G03X121199Y749124I-7124J7124D01*
G01D02*
Y1032799D01*
G01X116199Y751254D02*
G02X114499Y747150I-5804J0D01*
G01X117499Y751253D02*
G02X115419Y746230I-7105J0D01*
G01X104848Y746436D02*
Y751789D01*
G01X103861Y740912D02*
X103860Y740913D01*
G01D02*
G03X106148Y746437I-5523J5523D01*
G01D02*
Y751250D01*
G01X116199Y1029999D02*
Y751254D01*
G01X117499Y1030000D02*
Y751253D01*
G01X104848Y751789D02*
X104849Y751790D01*
G01D02*
Y928305D01*
G01X106148Y751250D02*
X106149Y751251D01*
G01D02*
Y913844D01*
G01D02*
G02X106374Y914069I225J0D01*
G01D02*
X106375D01*
G01D02*
G03X106600Y914294I0J225D01*
G01D02*
Y916244D01*
G01D02*
G03X106375Y916469I-225J0D01*
G01D02*
X106374D01*
G01D02*
G02X106149Y916694I0J225D01*
G01D02*
Y928305D01*
G01X104849D02*
G02X105579Y930070I2496J1D01*
G01D02*
G02X106983Y930650I1402J-1404D01*
G01D02*
X107399D01*
G01D02*
G03X108149Y930960I1J1060D01*
G01D02*
X108845Y931657D01*
G01X106149Y928305D02*
G02X106499Y929150I1195J0D01*
G01D02*
G02X106982Y929350I483J-483D01*
G01D02*
X107399D01*
G01D02*
G02X108424Y928926I1J-1449D01*
G01D02*
X109099Y928250D01*
G01X119899Y1032800D02*
G03X117919Y1037581I-6762J0D01*
G01X121199Y1032799D02*
G03X118839Y1038501I-8063J2D01*
G01D02*
X118470Y1038870D01*
G01D02*
X118469Y1038869D01*
G01X112901Y1037199D02*
X112900Y1037198D01*
G01D02*
X113440Y1036658D01*
G01D02*
G02X116199Y1029999I-6657J-6659D01*
G01X114360Y1037578D02*
G02X117499Y1030000I-7578J-7578D01*
G01X103772Y1335850D02*
X106799D01*
G01D02*
G03X108828Y1336691I-1J2870D01*
G01D02*
X109228Y1337090D01*
G01X103489Y1334550D02*
X106799D01*
G01D02*
G02X108838Y1333706I1J-2883D01*
G01D02*
X109228Y1333315D01*
G01X111309Y1360850D02*
G03X112999Y1361550I0J2390D01*
G01X110005Y1359550D02*
G02X111702Y1358847I0J-2400D01*
G01D02*
X112291Y1358258D01*
G01D02*
G03X112440Y1358196I149J148D01*
G01X103999Y1381050D02*
G02X104922Y1379044I-2250J-2250D01*
G01D02*
Y1377243D01*
G01D02*
G02X104200Y1375500I-2465J0D01*
G01X103623Y1378944D02*
X103622D01*
G01D02*
Y1377244D01*
G01X121349Y1406090D02*
G03X123045Y1401995I5790J-1D01*
G01D02*
X152245Y1372795D01*
G01X122649Y1406090D02*
G03X123964Y1402915I4490J0D01*
G01D02*
X153164Y1373715D01*
G01X121349Y1443518D02*
Y1406090D01*
G01X122649Y1443518D02*
Y1406090D01*
G01X117390Y1426201D02*
X116778Y1426813D01*
G01D02*
G03X114999Y1427550I-1779J-1779D01*
G01X119099Y1448950D02*
G02X121349Y1443518I-5433J-5432D01*
G01X120018Y1449870D02*
G02X122649Y1443518I-6352J-6352D01*
G01X104044Y1436050D02*
X107816D01*
G01D02*
G03X109647Y1436746I-1J2758D01*
G01D02*
G03X109999Y1437596I-850J850D01*
G01D02*
Y1442927D01*
G01D02*
G03X109849Y1443289I-512J0D01*
G01D02*
G03X108999Y1443641I-850J-850D01*
G01D02*
X107934D01*
G01D02*
G03X107053Y1443439I-1J-2018D01*
G01D02*
X106750Y1443135D01*
G01D02*
G03X106507Y1442550I585J-586D01*
G01D02*
Y1442050D01*
G01D02*
G02X106088Y1441040I-1429J1D01*
G01D02*
G02X105108Y1440634I-980J980D01*
G01D02*
X104935D01*
G01X104045Y1434750D02*
X107817D01*
G01D02*
G03X110687Y1435939I0J4059D01*
G01D02*
G03X111299Y1438188I-3826J2249D01*
G01D02*
Y1443050D01*
G01D02*
G03X110854Y1444124I-1519J0D01*
G01D02*
X110772Y1444206D01*
G01D02*
G03X108999Y1444940I-1773J-1773D01*
G01D02*
Y1444941D01*
G01D02*
X104999D01*
G01X117390Y1429976D02*
G02X114672Y1428850I-2718J2718D01*
G01D02*
X106499D01*
G01D02*
G02X106498Y1428849I-5124J5123D01*
G01X114999Y1427550D02*
X106369D01*
G01X125049Y1446349D02*
G03X123716Y1449567I-4552J0D01*
G01D02*
X110615Y1462668D01*
G01D02*
G02X108499Y1467777I5111J5110D01*
G01D02*
Y1684580D01*
G01X124635Y1450487D02*
X111535Y1463587D01*
G01D02*
G02X109799Y1467778I4191J4191D01*
G01D02*
Y1684580D01*
G01X103999Y1587237D02*
Y1467231D01*
G01D02*
G03X106248Y1461801I7681J1D01*
G01D02*
X119099Y1448950D01*
G01X105299Y1684107D02*
Y1467232D01*
G01D02*
G03X107168Y1462720I6381J0D01*
G01D02*
X120018Y1449870D01*
G01X130100Y1453651D02*
X118249Y1465502D01*
G01D02*
G02X115899Y1471176I5676J5675D01*
G01X131019Y1454571D02*
X119169Y1466421D01*
G01D02*
G02X117199Y1471177I4756J4756D01*
G01X112199Y1469973D02*
G03X114783Y1463734I8822J-1D01*
G01D02*
X127233Y1451284D01*
G01X128152Y1452204D02*
X115702Y1464654D01*
G01D02*
G02X113499Y1469973I5319J5319D01*
G01X124999Y1467117D02*
G03X123808Y1465926I0J-1191D01*
G01D02*
Y1465050D01*
G01X126279Y1468417D02*
G02X124290Y1469241I0J2813D01*
G01X115899Y1471176D02*
Y1647522D01*
G01X117199Y1471177D02*
Y1647522D01*
G01X112199Y1647667D02*
Y1469973D01*
G01X113499D02*
Y1647666D01*
G01X103999Y1596837D02*
Y1594935D01*
G01D02*
G02X103750Y1594686I-249J0D01*
G01D02*
X103749D01*
G01D02*
G03X103500Y1594437I0J-249D01*
G01D02*
Y1592535D01*
G01D02*
G03X103749Y1592286I249J0D01*
G01D02*
X103750D01*
G01D02*
G02X103999Y1592037I0J-249D01*
G01D02*
Y1590135D01*
G01D02*
G02X103750Y1589886I-249J0D01*
G01D02*
X103749D01*
G01D02*
G03X103500Y1589637I0J-249D01*
G01D02*
Y1587735D01*
G01D02*
G03X103749Y1587486I249J0D01*
G01D02*
X103750D01*
G01D02*
G02X103999Y1587237I0J-249D01*
G01Y1684106D02*
Y1599735D01*
G01D02*
G02X103750Y1599486I-249J0D01*
G01D02*
X103749D01*
G01D02*
G03X103500Y1599237I0J-249D01*
G01D02*
Y1597335D01*
G01D02*
G03X103749Y1597086I249J0D01*
G01D02*
X103750D01*
G01D02*
G02X103999Y1596837I0J-249D01*
G01X115899Y1647522D02*
G02X118397Y1653553I8528J1D01*
G01D02*
X149796Y1684952D01*
G01X117199Y1647522D02*
G02X119316Y1652633I7228J0D01*
G01D02*
X150716Y1684033D01*
G01X144279Y1684669D02*
X115679Y1656069D01*
G01D02*
G03X112199Y1647667I8404J-8403D01*
G01X113499Y1647666D02*
G02X116599Y1655150I10584J0D01*
G01D02*
X145198Y1683749D01*
G01X108499Y1684580D02*
G03X107541Y1686893I-3271J0D01*
G01X109799Y1684580D02*
G03X108460Y1687813I-4571J1D01*
G01D02*
X103561Y1692712D01*
G01X104144Y1686895D02*
G02X105299Y1684107I-2788J-2788D01*
G01X105883Y1741850D02*
G03X105973I45J4626D01*
G01D02*
G03X109154Y1743205I-91J4625D01*
G01D02*
X109499Y1743550D01*
G01X105599Y1740550D02*
X105999D01*
G01D02*
G03X107782Y1740861I-115J5925D01*
G01D02*
G02X109399Y1739701I392J-1160D01*
G01D02*
Y1739550D01*
G01X124734Y1872200D02*
G03X123393Y1870859I0J-1341D01*
G01X125412Y1873500D02*
G02X123592Y1874254I0J2574D01*
G01X129399Y233200D02*
X819160D01*
G01X129399Y231901D02*
Y231900D01*
G01D02*
X819160D01*
G01X126249Y239100D02*
X126928Y238420D01*
G01D02*
G03X130599Y236900I3670J3671D01*
G01D02*
X816263D01*
G01X125479Y238031D02*
X126008Y237501D01*
G01D02*
G03X130599Y235600I4590J4591D01*
G01D02*
X816263D01*
G01X131729Y248980D02*
X138329Y242380D01*
G01D02*
G03X140334Y241550I2005J2007D01*
G01D02*
X148475D01*
G01X126917Y257469D02*
X127018Y257367D01*
G01D02*
G02X127799Y255483I-1884J-1885D01*
G01D02*
Y252350D01*
G01D02*
G02X125499Y250050I-2300J0D01*
G01X125998Y256550D02*
X126114Y256433D01*
G01D02*
G02X126499Y255505I-928J-929D01*
G01D02*
Y252350D01*
G01D02*
G02X125499Y251350I-1000J0D01*
G01X127956Y261667D02*
X127961D01*
G01D02*
X130016Y259607D01*
G01D02*
X130386Y259237D01*
G01D02*
G02X131499Y256550I-2687J-2687D01*
G01D02*
Y252676D01*
G01D02*
G03X132649Y249900I3926J0D01*
G01D02*
X139249Y243300D01*
G01D02*
G03X140335Y242850I1086J1086D01*
G01D02*
X148420D01*
G01X127415Y260367D02*
X127421D01*
G01D02*
X129289Y258494D01*
G01D02*
X129468Y258315D01*
G01D02*
G02X130199Y256550I-1765J-1765D01*
G01D02*
Y252675D01*
G01D02*
G03X131356Y249396I5226J1D01*
G01D02*
G03X131729Y248980I4072J3276D01*
G01X157779Y703910D02*
X126840Y652679D01*
G01D02*
X126831Y652663D01*
G01D02*
X125168Y649909D01*
G01X158893Y703238D02*
X127954Y652007D01*
G01D02*
X125902Y648609D01*
G01X129892Y712516D02*
G03Y712854I-169J169D01*
G01D02*
G02Y713192I169J169D01*
G01D02*
X131252Y714552D01*
G01D02*
G02X131590I169J-169D01*
G01D02*
G03X131928I169J169D01*
G01D02*
X146112Y728736D01*
G01X134581Y744167D02*
X134582D01*
G01D02*
G03X135714Y746900I-2733J2733D01*
G01D02*
Y768692D01*
G01X135501Y743247D02*
Y743248D01*
G01D02*
G03X137014Y746901I-3652J3652D01*
G01D02*
Y768691D01*
G01X132014Y770462D02*
Y748849D01*
G01D02*
G02X131460Y747510I-1893J-1D01*
G01D02*
X130499Y746550D01*
G01X133314Y770461D02*
Y748849D01*
G01D02*
G02X132380Y746590I-3194J-2D01*
G01D02*
X131419Y745630D01*
G01X141679Y739769D02*
G03X143684Y744609I-4840J4840D01*
G01D02*
Y766031D01*
G01X142599Y738850D02*
G03X144984Y744608I-5760J5759D01*
G01D02*
Y766031D01*
G01X139567Y766750D02*
Y744933D01*
G01D02*
G02X138849Y743200I-2451J0D01*
G01X139768Y742280D02*
Y742281D01*
G01D02*
G03X140867Y744932I-2652J2653D01*
G01D02*
Y766866D01*
G01X135714Y768692D02*
G02X137249Y772398I5243J-1D01*
G01X137014Y768691D02*
G02X138169Y771479I3943J0D01*
G01D02*
X179119Y812429D01*
G01X133382Y773765D02*
G03X132014Y770462I3305J-3304D01*
G01X134302Y772846D02*
G03X133314Y770461I2385J-2385D01*
G01X143684Y766031D02*
G02X145334Y770015I5633J1D01*
G01D02*
X185434Y810115D01*
G01X144984Y766031D02*
G02X146253Y769095I4333J0D01*
G01X182117Y812032D02*
X141499Y771414D01*
G01D02*
G03X139567Y766750I4664J-4664D01*
G01X140867Y766866D02*
G02X142336Y770412I5015J0D01*
G01D02*
X183037Y811113D01*
G01X137249Y772398D02*
X178200Y813349D01*
G01X174533Y814916D02*
X133382Y773765D01*
G01X175453Y813997D02*
X134302Y772846D01*
G01X155861Y1374413D02*
X127120Y1403154D01*
G01D02*
G02X125049Y1408154I5002J5001D01*
G01X156781Y1375332D02*
X128040Y1404073D01*
G01D02*
G02X126349Y1408155I4082J4082D01*
G01X163046Y1377696D02*
X135046Y1405696D01*
G01D02*
G02X132449Y1411966I6269J6269D01*
G01X163965Y1378616D02*
X135965Y1406616D01*
G01X128749Y1409629D02*
G03X130778Y1404730I6930J1D01*
G01D02*
X159578Y1375930D01*
G01X160498Y1376849D02*
X131698Y1405649D01*
G01D02*
G02X130049Y1409630I3981J3981D01*
G01X166312Y1379664D02*
X138463Y1407513D01*
G01X167231Y1380584D02*
X139382Y1408433D01*
G01X125049Y1408154D02*
Y1446349D01*
G01X126349Y1408155D02*
Y1446349D01*
G01X132449Y1411966D02*
Y1447980D01*
G01X135965Y1406616D02*
G02X133749Y1411966I5350J5350D01*
G01D02*
Y1447980D01*
G01X128749Y1447625D02*
Y1409629D01*
G01X130049Y1409630D02*
Y1447624D01*
G01X138463Y1407513D02*
G02X136149Y1413100I5586J5586D01*
G01D02*
Y1446700D01*
G01X139382Y1408433D02*
G02X137449Y1413100I4667J4667D01*
G01D02*
Y1446161D01*
G01X126349Y1446349D02*
G03X124635Y1450487I-5852J0D01*
G01X132449Y1447980D02*
G03X130100Y1453651I-8020J0D01*
G01X133749Y1447980D02*
G03X131019Y1454571I-9320J0D01*
G01X127233Y1451284D02*
G02X128748Y1447624I-3662J-3659D01*
G01D02*
X128749Y1447625D01*
G01X130049Y1447624D02*
G03X128152Y1452204I-6477J0D01*
G01X136149Y1446700D02*
X136150Y1446701D01*
G01D02*
Y1451399D01*
G01X137449Y1446161D02*
X137450Y1446162D01*
G01D02*
Y1451938D01*
G01X172748Y1435961D02*
X143074Y1465635D01*
G01D02*
G03X139498Y1467117I-3576J-3574D01*
G01D02*
X124999D01*
G01X173699Y1436850D02*
X143994Y1466555D01*
G01D02*
G03X139499Y1468417I-4495J-4495D01*
G01D02*
X126279D01*
G01X136150Y1451399D02*
X136149Y1451400D01*
G01D02*
Y1454210D01*
G01D02*
G02X137230Y1456820I3690J0D01*
G01D02*
X137829Y1457419D01*
G01D02*
G02X140560Y1458550I2730J-2730D01*
G01D02*
X141450D01*
G01D02*
G03X142900Y1460000I0J1450D01*
G01X137450Y1451938D02*
X137449Y1451939D01*
G01D02*
Y1454210D01*
G01D02*
G02X138149Y1455900I2390J0D01*
G01D02*
X138150D01*
G01D02*
X138749Y1456499D01*
G01D02*
G02X139874Y1457156I1811J-1810D01*
G01D02*
G02X140559Y1457250I687J-2467D01*
G01D02*
X141450D01*
G01D02*
G02X142597Y1456775I0J-1622D01*
G01D02*
X142999Y1456373D01*
G01X147499Y1692442D02*
G02X144279Y1684669I-10994J1D01*
G01X145198Y1683749D02*
G03X148799Y1692443I-8693J8693D01*
G01X133845Y1815854D02*
X145801Y1803899D01*
G01X146524Y1805014D02*
X134765Y1816774D01*
G01X131600Y1860420D02*
Y1821278D01*
G01D02*
G03X133846Y1815855I7668J-1D01*
G01D02*
X133845Y1815854D01*
G01X134765Y1816774D02*
G02X132900Y1821277I4503J4503D01*
G01D02*
Y1860421D01*
G01X147601Y1863700D02*
G03X145478Y1868819I-7241J-3D01*
G01D02*
X144248Y1870049D01*
G01D02*
Y1870051D01*
G01D02*
X143863Y1870436D01*
G01D02*
G03X139605Y1872200I-4258J-4256D01*
G01X146250Y1869888D02*
X144782Y1871356D01*
G01X137999Y1865151D02*
X137247Y1864400D01*
G01D02*
G02X135800Y1863800I-1448J1447D01*
G01D02*
X135199D01*
G01D02*
G03X132644Y1862742I0J-3614D01*
G01D02*
X132501Y1862599D01*
G01D02*
X132502Y1862598D01*
G01D02*
G03X131600Y1860420I2177J-2177D01*
G01X132900Y1860421D02*
G02X133421Y1861679I1779J0D01*
G01D02*
X133564Y1861822D01*
G01D02*
G02X135200Y1862500I1636J-1635D01*
G01D02*
X136300D01*
G01D02*
G02X137488Y1862008I0J-1680D01*
G01D02*
X137999Y1861497D01*
G01X139605Y1872200D02*
X124734D01*
G01X144782Y1871356D02*
G03X139606Y1873500I-5176J-5176D01*
G01D02*
X125412D01*
G01X148475Y241550D02*
G02X149199Y241250I0J-1024D01*
G01D02*
X149489Y240960D01*
G01D02*
G02X149999Y239729I-1231J-1231D01*
G01X148420Y242850D02*
G03X149999Y243504I0J2233D01*
G01X153699Y441512D02*
G03X156182Y441893I0J8281D01*
G01D02*
X163612Y444122D01*
G01D02*
G03X169426Y446565I-8473J28305D01*
G01X153699Y440212D02*
G03X156571Y440652I2J9582D01*
G01D02*
X163985Y442877D01*
G01D02*
G03X170055Y445427I-8844J29551D01*
G01X161491Y710056D02*
X159317Y706457D01*
G01D02*
X157779Y703910D01*
G01X163141Y710272D02*
X160430Y705784D01*
G01D02*
X158893Y703238D01*
G01X147999Y707550D02*
G03X152551Y718540I-10990J10990D01*
G01X172846Y728859D02*
X161491Y710056D01*
G01X173941Y728157D02*
X163141Y710272D01*
G01X147079Y708470D02*
G03X151250Y718540I-10070J10070D01*
G01D02*
X151251Y718539D01*
G01D02*
Y763389D01*
G01X152551Y718540D02*
Y763390D01*
G01X146112Y728736D02*
G03X147551Y732210I-3474J3474D01*
G01X147032Y727817D02*
G03X148851Y732209I-4394J4393D01*
G01X147551Y732210D02*
Y764170D01*
G01X148851Y732209D02*
Y764169D01*
G01X146253Y769095D02*
X186353Y809195D01*
G01X151251Y763389D02*
G02X152718Y766931I5008J1D01*
G01D02*
X192868Y807081D01*
G01X152551Y763390D02*
G02X153637Y766011I3708J-1D01*
G01D02*
X193787Y806161D01*
G01X147551Y764170D02*
G02X149551Y768997I6827J-1D01*
G01D02*
Y768998D01*
G01D02*
X189601Y809048D01*
G01X148851Y764169D02*
G02X150470Y768079I5529J1D01*
G01D02*
X150670Y768278D01*
G01D02*
X190521Y808129D01*
G01X178772Y1174123D02*
X158221Y1194674D01*
G01X179691Y1175043D02*
X159141Y1195593D01*
G01X152699Y1197515D02*
G03X154504Y1193157I6165J1D01*
G01D02*
X175154Y1172507D01*
G01X153999Y1197516D02*
G03X155424Y1194076I4865J0D01*
G01D02*
X176074Y1173426D01*
G01X162039Y1196090D02*
X183188Y1174941D01*
G01X184108Y1175860D02*
X162958Y1197010D01*
G01X158221Y1194674D02*
G02X156399Y1199073I4401J4400D01*
G01D02*
Y1373115D01*
G01X159141Y1195593D02*
G02X157699Y1199074I3481J3481D01*
G01D02*
Y1373116D01*
G01X152699Y1371700D02*
Y1197515D01*
G01X153999Y1371699D02*
Y1197516D01*
G01X186306Y1177057D02*
X165305Y1198058D01*
G01D02*
G02X163799Y1201694I3638J3637D01*
G01D02*
Y1375878D01*
G01X187225Y1177977D02*
X166225Y1198977D01*
G01D02*
G02X165099Y1201695I2718J2718D01*
G01D02*
Y1375878D01*
G01X160099Y1374673D02*
Y1200774D01*
G01D02*
G03X162039Y1196090I6623J-1D01*
G01X162958Y1197010D02*
G02X161399Y1200774I3764J3764D01*
G01D02*
Y1374674D01*
G01X156399Y1373115D02*
G03X155861Y1374413I-1834J0D01*
G01X157699Y1373116D02*
G03X156781Y1375332I-3134J0D01*
G01X152245Y1372795D02*
G02X152698Y1371699I-1098J-1095D01*
G01D02*
X152699Y1371700D01*
G01X153164Y1373715D02*
G02X153999Y1371699I-2016J-2016D01*
G01X163799Y1375878D02*
X163798D01*
G01D02*
G03X163046Y1377696I-2572J1D01*
G01X165099Y1375878D02*
G03X163965Y1378616I-3872J0D01*
G01X159578Y1375930D02*
G02X160099Y1374673I-1255J-1257D01*
G01X161399Y1374674D02*
G03X160498Y1376849I-3076J0D01*
G01X167499Y1376798D02*
G03X166312Y1379664I-4053J0D01*
G01X149796Y1684952D02*
G03X153249Y1693288I-8336J8336D01*
G01D02*
Y1752099D01*
G01X150716Y1684033D02*
G03X154549Y1693287I-9256J9255D01*
G01D02*
Y1801600D01*
G01X147499Y1799800D02*
Y1692442D01*
G01X148799Y1692443D02*
Y1799801D01*
G01X153249Y1752099D02*
G03X152924Y1752424I-325J0D01*
G01D02*
G02X152599Y1752749I0J325D01*
G01D02*
Y1754499D01*
G01D02*
G02X152924Y1754824I325J0D01*
G01D02*
G03X153249Y1755149I0J325D01*
G01D02*
Y1756899D01*
G01D02*
G03X152924Y1757224I-325J0D01*
G01D02*
G02X152599Y1757549I0J325D01*
G01D02*
Y1759299D01*
G01D02*
G02X152924Y1759624I325J0D01*
G01D02*
G03X153249Y1759949I0J325D01*
G01D02*
Y1761699D01*
G01D02*
G03X152924Y1762024I-325J0D01*
G01D02*
G02X152599Y1762349I0J325D01*
G01D02*
Y1764099D01*
G01D02*
G02X152924Y1764424I325J0D01*
G01D02*
G03X153249Y1764749I0J325D01*
G01D02*
Y1766499D01*
G01D02*
G03X152924Y1766824I-325J0D01*
G01D02*
G02X152599Y1767149I0J325D01*
G01D02*
Y1768899D01*
G01D02*
G02X152924Y1769224I325J0D01*
G01D02*
G03X153249Y1769549I0J325D01*
G01D02*
Y1801600D01*
G01D02*
X153250D01*
G01D02*
G03X151941Y1804759I-4469J-1D01*
G01D02*
X151584Y1805115D01*
G01D02*
X149006Y1807692D01*
G01D02*
X149007Y1807693D01*
G01D02*
G02X147600Y1811090I3396J3396D01*
G01X154549Y1801600D02*
G03X152860Y1805679I-5768J1D01*
G01D02*
X152503Y1806035D01*
G01D02*
X149926Y1808612D01*
G01X145801Y1803899D02*
G02X147499Y1799800I-4099J-4099D01*
G01X148799Y1799801D02*
G03X146721Y1804819I-7098J0D01*
G01D02*
X146525Y1805015D01*
G01D02*
X146524Y1805014D01*
G01X147600Y1811090D02*
Y1863700D01*
G01X149926Y1808612D02*
G02X148900Y1811089I2477J2477D01*
G01D02*
Y1863700D01*
G01X147600D02*
X147601D01*
G01X148900D02*
G03X146398Y1869739I-8541J-1D01*
G01D02*
X146250Y1869888D01*
G01X169426Y446565D02*
X171373Y448205D01*
G01D02*
X171374D01*
G01D02*
X179844Y455342D01*
G01X170055Y445427D02*
G02X170161Y445484I2582J-4675D01*
G01D02*
X171848Y446905D01*
G01D02*
X171849D01*
G01D02*
X180630Y454302D01*
G01X174593Y462200D02*
G03X180254Y464545I0J8006D01*
G01D02*
X777376Y1061667D01*
G01X778296Y1060747D02*
X181173Y463625D01*
G01D02*
Y463626D01*
G01D02*
G02X174594Y460900I-6581J6580D01*
G01X172225Y466000D02*
G03X178924Y468775I0J9474D01*
G01D02*
X179403Y469254D01*
G01D02*
X179404D01*
G01D02*
X774419Y1064270D01*
G01X775339Y1063350D02*
X179943Y467954D01*
G01D02*
X179942D01*
G01D02*
X179843Y467855D01*
G01D02*
G02X172226Y464700I-7618J7619D01*
G01X179844Y455342D02*
X179869Y455363D01*
G01D02*
X180699Y455862D01*
G01D02*
X180754Y455884D01*
G01D02*
X181439Y456157D01*
G01D02*
X181843Y456317D01*
G01D02*
X181949D01*
G01D02*
X834074Y661025D01*
G01X180630Y454302D02*
X181279Y454693D01*
G01D02*
X181877Y454932D01*
G01D02*
X181881D01*
G01D02*
X182339Y455076D01*
G01D02*
X182810Y455224D01*
G01D02*
X834463Y659784D01*
G01X195529Y762265D02*
X172846Y728859D01*
G01X196628Y761569D02*
X173941Y728157D01*
G01X178200Y813349D02*
G03X179699Y816968I-3619J3619D01*
G01X179119Y812429D02*
G03X180999Y816968I-4538J4538D01*
G01X185434Y810115D02*
G03X187399Y814859I-4744J4744D01*
G01X186353Y809195D02*
G03X188699Y814859I-5663J5663D01*
G01X183699Y815851D02*
G02X182117Y812032I-5401J0D01*
G01X183037Y811113D02*
G03X184999Y815850I-4739J4738D01*
G01X179699Y816968D02*
Y1171886D01*
G01X180999Y816968D02*
Y1171885D01*
G01X175999Y1170468D02*
Y818455D01*
G01D02*
G02X174533Y814916I-5005J0D01*
G01X177299Y1170469D02*
Y818454D01*
G01D02*
G02X175453Y813997I-6305J1D01*
G01X187399Y814859D02*
Y1174418D01*
G01X183699Y1173708D02*
Y815851D01*
G01X184999Y815850D02*
Y1173709D01*
G01X179699Y1171886D02*
X179698Y1171885D01*
G01D02*
G03X178772Y1174123I-3166J1D01*
G01X180999Y1171885D02*
G03X179691Y1175043I-4466J0D01*
G01X175154Y1172507D02*
G02X175999Y1170468I-2037J-2039D01*
G01X176074Y1173426D02*
G02X177299Y1170469I-2957J-2957D01*
G01X187399Y1174418D02*
X187398D01*
G01D02*
G03X186306Y1177057I-3733J1D01*
G01X188699Y1174418D02*
G03X187225Y1177977I-5033J0D01*
G01X183188Y1174941D02*
G02X183699Y1173708I-1231J-1233D01*
G01X184999Y1173709D02*
G03X184108Y1175860I-3042J0D01*
G01X193739Y1180092D02*
X173289Y1200542D01*
G01X194659Y1181011D02*
X174209Y1201461D01*
G01X189972Y1178625D02*
X169523Y1199074D01*
G01X190892Y1179544D02*
X170442Y1199994D01*
G01X173289Y1200542D02*
G02X171199Y1205588I5048J5047D01*
G01D02*
Y1384723D01*
G01X174209Y1201461D02*
G02X172499Y1205589I4128J4128D01*
G01D02*
Y1384722D01*
G01X169523Y1199074D02*
G02X167499Y1203961I4886J4886D01*
G01D02*
Y1376798D01*
G01X170442Y1199994D02*
G02X168799Y1203961I3967J3967D01*
G01D02*
Y1376798D01*
G01X171199Y1384723D02*
G02X172466Y1387782I4328J-1D01*
G01X172499Y1384722D02*
G02X173386Y1386863I3028J0D01*
G01X168799Y1376798D02*
G03X167231Y1380584I-5353J1D01*
G01X172466Y1387782D02*
X172966Y1388282D01*
G01D02*
G03X173872Y1390469I-2187J2187D01*
G01D02*
Y1423987D01*
G01X173386Y1386863D02*
X173886Y1387363D01*
G01D02*
G03X175172Y1390468I-3107J3106D01*
G01D02*
Y1433294D01*
G01X173872Y1423987D02*
G03X173636Y1424223I-236J0D01*
G01D02*
G02X173400Y1424459I0J236D01*
G01D02*
Y1426387D01*
G01D02*
G02X173636Y1426623I236J0D01*
G01D02*
G03X173872Y1426859I0J236D01*
G01D02*
Y1433250D01*
G01D02*
G03X172748Y1435961I-3834J-1D01*
G01X175172Y1433294D02*
G03X173699Y1436850I-5029J0D01*
G01X192400Y764246D02*
X817275Y1826081D01*
G01X818397Y1825421D02*
X193499Y763550D01*
G01X291338Y925070D02*
X195529Y762265D01*
G01X292455Y924404D02*
X196628Y761569D01*
G01X192868Y807081D02*
G03X194799Y811743I-4662J4662D01*
G01D02*
Y1177534D01*
G01X193787Y806161D02*
G03X196099Y811743I-5581J5581D01*
G01D02*
Y1177535D01*
G01X189601Y809048D02*
Y809049D01*
G01D02*
G03X191099Y812662I-3613J3615D01*
G01D02*
Y1175905D01*
G01X190521Y808129D02*
G03X192399Y812663I-4534J4534D01*
G01D02*
Y1175906D01*
G01X188699Y814859D02*
Y1174418D01*
G01X194799Y1177534D02*
G03X193739Y1180092I-3616J0D01*
G01X196099Y1177535D02*
G03X194659Y1181011I-4916J0D01*
G01X191099Y1175905D02*
G03X189972Y1178625I-3845J0D01*
G01X192399Y1175906D02*
G03X190892Y1179544I-5145J0D01*
G01X276099Y432336D02*
G03X280296Y432766I-1J20709D01*
G01D02*
G03X280387Y432785I-4050J19624D01*
G01D02*
G03X283100Y433563I-4105J19433D01*
G01X276099Y433636D02*
G03X280120Y434048I1J19820D01*
G01D02*
G03X282747Y434823I-3365J16247D01*
G01D02*
X832854Y655926D01*
G01X283100Y433563D02*
X283833Y433857D01*
G01D02*
X833339Y654720D01*
G01X812802Y1788567D02*
X291338Y925070D01*
G01X813914Y1787894D02*
X292455Y924404D01*
G01X777376Y1061667D02*
G02X781299Y1063292I3923J-3923D01*
G01Y1061992D02*
G03X778296Y1060747I1J-4247D01*
G01X774419Y1064270D02*
G02X781489Y1067199I7071J-7071D01*
G01X781490Y1065899D02*
G03X775339Y1063350I1J-8699D01*
G01X781299Y1063292D02*
X847999D01*
G01X846026Y1061992D02*
X781299D01*
G01X781489Y1067199D02*
X867281D01*
G01X867280Y1065899D02*
X781490D01*
G01X819160Y233200D02*
G03X823409Y234960I0J6010D01*
G01X819160Y231900D02*
G03X824329Y234041I0J7310D01*
G01X816263Y236900D02*
G03X820505Y238657I0J5999D01*
G01D02*
X835633Y253783D01*
G01X816263Y235600D02*
G03X821425Y237737I1J7300D01*
G01D02*
X836553Y252863D01*
G01X832229Y1471219D02*
X818030Y1457020D01*
G01D02*
X817202Y1455998D01*
G01X833149Y1470300D02*
X818949Y1456100D01*
G01D02*
X818955Y1456096D01*
G01D02*
X818212Y1455180D01*
G01X856708Y1861271D02*
X815549Y1793112D01*
G01D02*
X812802Y1788567D01*
G01X857822Y1860600D02*
X817226Y1793374D01*
G01D02*
X813914Y1787894D01*
G01X817275Y1826081D02*
X843620Y1870848D01*
G01X844804Y1870294D02*
X818397Y1825421D01*
G01X823409Y234960D02*
X838549Y250100D01*
G01X824329Y234041D02*
X839468Y249180D01*
G01X838549Y250100D02*
X839434Y250984D01*
G01D02*
G02X841499Y251840I2066J-2065D01*
G01D02*
X848580D01*
G01X839468Y249180D02*
X840354Y250064D01*
G01D02*
G02X841499Y250541I1148J-1144D01*
G01D02*
Y250540D01*
G01D02*
X846671D01*
G01X835633Y253783D02*
G02X839875Y255540I4242J-4242D01*
G01D02*
X859118D01*
G01X836553Y252863D02*
G02X839875Y254240I3323J-3322D01*
G01D02*
X859116D01*
G01X832854Y655926D02*
X832925Y655955D01*
G01D02*
X833847Y656326D01*
G01D02*
G02X839299Y657600I5452J-11029D01*
G01D02*
X847629D01*
G01X833339Y654720D02*
X834423Y655160D01*
G01D02*
G02X839299Y656300I4876J-9858D01*
G01D02*
X846842D01*
G01X834074Y661025D02*
G02X835871Y661300I1796J-5725D01*
G01D02*
X849603D01*
G01X834463Y659784D02*
G02X835871Y660000I1408J-4484D01*
G01D02*
X849603D01*
G01X834716Y1457033D02*
X845209Y1467526D01*
G01X835640Y1456108D02*
X835635Y1456113D01*
G01D02*
X846135Y1466613D01*
G01X853299Y1472550D02*
X835443D01*
G01D02*
G03X832229Y1471219I-1J-4544D01*
G01X853607Y1471250D02*
X835443D01*
G01D02*
G03X833149Y1470300I0J-3244D01*
G01X843620Y1870848D02*
X843997Y1871486D01*
G01X848580Y251840D02*
G02X850000Y251252I0J-2008D01*
G01D02*
X851278Y249974D01*
G01X846671Y250540D02*
G02X847878Y250040I0J-1707D01*
G01X859118Y255540D02*
G02X861218Y254670I0J-2970D01*
G01D02*
X873018Y242870D01*
G01X859116Y254240D02*
G02X860299Y253750I0J-1673D01*
G01D02*
X871899Y242150D01*
G01X847629Y657600D02*
G02X849976Y656628I0J-3319D01*
G01D02*
X851172Y655432D01*
G01X846842Y656300D02*
G02X847772Y655370I0J-930D01*
G01X849603Y661300D02*
G02X853845Y659543I0J-5999D01*
G01D02*
X864618Y648770D01*
G01D02*
G03X866639Y647933I2021J2021D01*
G01X849603Y660000D02*
G02X852925Y658623I-1J-4699D01*
G01D02*
X863698Y647850D01*
G01D02*
G03X866636Y646633I2938J2938D01*
G01X847999Y1063292D02*
G02X849677Y1062597I0J-2373D01*
G01D02*
X850833Y1061441D01*
G01X847233Y1061492D02*
G03X846962Y1061711I-1202J-1211D01*
G01D02*
G03X846291Y1061971I-938J-1425D01*
G01D02*
G03X846026Y1061992I-267J-1686D01*
G01X845209Y1467526D02*
G02X846284Y1468224I2187J-2192D01*
G01D02*
G02X851521Y1467113I1764J-4584D01*
G01D02*
X852288Y1466346D01*
G01X846135Y1466613D02*
G02X846751Y1467014I1255J-1255D01*
G01D02*
G02X848686Y1466605I653J-1691D01*
G01D02*
X848888Y1466402D01*
G01X869418Y1459470D02*
X858487Y1470401D01*
G01X868149Y1458900D02*
X857349Y1469700D01*
G01X858487Y1470401D02*
G03X853299Y1472550I-5188J-5188D01*
G01X857349Y1469700D02*
G03X853607Y1471250I-3742J-3742D01*
G01X852536Y1871999D02*
X853499Y1871036D01*
G01X850099Y1871056D02*
G03X849603Y1871721I-694J0D01*
G01X846260Y1871750D02*
G03X845357Y1871233I0J-1048D01*
G01D02*
X844804Y1870294D01*
G01X865067Y1864850D02*
X863498D01*
G01D02*
G03X857895Y1862530I0J-7926D01*
G01D02*
X856960Y1861594D01*
G01D02*
G03X856708Y1861271I1204J-1199D01*
G01X865999Y1863549D02*
X863498D01*
G01D02*
G03X858815Y1861610I0J-6625D01*
G01D02*
X857881Y1860676D01*
G01D02*
G03X857822Y1860600I284J-281D01*
G01X843997Y1871486D02*
X844236Y1871893D01*
G01D02*
G02X846259Y1873050I2024J-1191D01*
G01D02*
X849999D01*
G01D02*
G02X852536Y1871999I0J-3588D01*
G01X849603Y1871721D02*
G03X849405Y1871750I-199J-665D01*
G01D02*
X846260D01*
G01X873018Y242870D02*
G03X874273Y242350I1255J1255D01*
G01D02*
X875999D01*
G01D02*
G03X876939Y242740I-1J1330D01*
G01X871899Y242150D02*
G03X874555Y241050I2656J2656D01*
G01D02*
X876199D01*
G01D02*
G02X876593Y241015I-1J-2250D01*
G01D02*
G02X877571Y240610I0J-1383D01*
G01D02*
X878078Y240103D01*
G01X876939Y242740D02*
X878078Y243878D01*
G01X866639Y647933D02*
X876521D01*
G01D02*
G03X877648Y648400I0J1594D01*
G01D02*
X878596Y649348D01*
G01X866636Y646633D02*
X877079D01*
G01D02*
G02X877859Y646310I0J-1103D01*
G01D02*
X878596Y645573D01*
G01X867281Y1067199D02*
G02X869510Y1066277I-1J-3158D01*
G01D02*
X869627Y1066161D01*
G01D02*
G02X870438Y1064205I-1948J-1954D01*
G01D02*
Y1055550D01*
G01D02*
G03X871102Y1053947I2267J0D01*
G01D02*
X871299Y1053750D01*
G01D02*
G03X872748Y1053150I1449J1449D01*
G01D02*
X874999D01*
G01D02*
G03X877781Y1054303I-1J3935D01*
G01D02*
X877964Y1054485D01*
G01X878233Y1051095D02*
X878232Y1051216D01*
G01D02*
G03X876837Y1052183I-1033J0D01*
G01D02*
G02X875000Y1051850I-1837J4902D01*
G01D02*
X872749D01*
G01D02*
G02X870379Y1052830I-3J3349D01*
G01D02*
X870182Y1053027D01*
G01D02*
G02X869138Y1055550I2523J2522D01*
G01D02*
Y1064206D01*
G01D02*
G03X868710Y1065239I-1459J1D01*
G01D02*
X868593Y1065355D01*
G01D02*
G03X867280Y1065899I-1314J-1314D01*
G01X877853Y1459991D02*
G02X876612Y1458750I-1241J0D01*
G01D02*
X871156D01*
G01D02*
G02X869418Y1459470I0J2458D01*
G01X878054Y1456450D02*
G03X877054Y1457450I-1000J0D01*
G01D02*
X871650D01*
G01D02*
G02X868149Y1458900I0J4951D01*
G01X866914Y1865615D02*
G02X865067Y1864850I-1847J1847D01*
G01X866914Y1861840D02*
Y1862634D01*
G01D02*
G03X865999Y1863549I-915J0D01*
G54D12*
G01X1019291Y1620020D02*
Y1676496D01*
G02X1024213Y1681417I4921J0D01*
G01X1029528D01*
X1033465Y1685354D01*
Y1988189D01*
G03X1029528Y1992126I-3937J0D01*
G01X3937D01*
G03X0Y1988189I0J-3937D01*
G01Y1818701D01*
X3937Y1814764D01*
X19882D01*
G02Y1807283I0J-3740D01*
G01X3937D01*
X0Y1803346D01*
Y1409252D01*
X3937Y1405315D01*
X19882D01*
G02Y1397835I0J-3740D01*
G01X3937D01*
X0Y1393898D01*
Y834449D01*
X3937Y830512D01*
X19882D01*
G02Y823031I0J-3740D01*
G01X3937D01*
X0Y819094D01*
Y425000D01*
X3937Y421063D01*
X19882D01*
G02Y413583I0J-3740D01*
G01X3937D01*
X0Y409646D01*
Y3937D01*
G03X3937Y0I3937J0D01*
G01X1029528D01*
G03X1033465Y3937I0J3937D01*
G01Y1424882D01*
X1029528Y1428819D01*
X1024213D01*
G02X1019291Y1433740I-1J4921D01*
G01Y1607933D01*
X1015354Y1611870D01*
X989744D01*
G02Y1616083I0J2107D01*
G01X1015354D01*
X1019291Y1620020D01*
G01X24705Y1903150D02*
G02X10728I-6989J0D01*
G02X24705I6988J0D01*
G01X30639Y-130979D02*
Y-142979D01*
G01X28339Y-130979D02*
X32939D01*
G01X34939Y-142979D02*
Y-130979D01*
G01Y-136779D02*
X35439Y-135779D01*
X35939Y-135179D01*
X36739Y-134979D01*
X37339Y-135179D01*
X38039Y-135979D01*
X38339Y-137179D01*
Y-142979D01*
G01X42639Y-134979D02*
Y-142979D01*
G01Y-131779D02*
X42439Y-131579D01*
Y-131179D01*
X42639Y-130979D01*
X42839Y-131179D01*
Y-131579D01*
X42639Y-131779D01*
G01X47139Y-141579D02*
X47639Y-142379D01*
X48339Y-142979D01*
X48939D01*
X49539Y-142579D01*
X49939Y-141979D01*
X50139Y-141179D01*
X50039Y-139979D01*
X49639Y-139379D01*
X47839Y-138179D01*
X47439Y-136779D01*
X47639Y-135779D01*
X48039Y-135179D01*
X48639Y-134979D01*
X49239Y-135179D01*
X49839Y-135779D01*
G01X59239Y-145979D02*
X59939Y-146779D01*
X60739Y-146979D01*
X61439Y-146779D01*
X62039Y-145779D01*
X62439Y-144379D01*
Y-134979D01*
G01Y-136579D02*
X62039Y-135779D01*
X61439Y-135179D01*
X60739Y-134979D01*
X59939Y-135379D01*
X59439Y-136179D01*
X59039Y-137579D01*
X58839Y-138979D01*
X58939Y-140179D01*
X59339Y-141579D01*
X59939Y-142579D01*
X60739Y-142979D01*
X61339Y-142779D01*
X62039Y-141979D01*
X62439Y-141179D01*
G01X65139Y-137579D02*
X68339D01*
X68039Y-136179D01*
X67539Y-135379D01*
X66839Y-134979D01*
X66139Y-135179D01*
X65539Y-135779D01*
X65139Y-137179D01*
X64939Y-138379D01*
Y-139579D01*
X65139Y-140779D01*
X65639Y-141979D01*
X66239Y-142779D01*
X66939Y-142979D01*
X67639Y-142579D01*
X68339Y-141379D01*
G01X71239Y-142979D02*
Y-134979D01*
G01Y-136579D02*
X71739Y-135779D01*
X72239Y-135179D01*
X72939Y-134979D01*
X73439Y-135179D01*
X74039Y-135779D01*
G01X76839Y-142979D02*
Y-130979D01*
G01Y-136979D02*
X77339Y-135779D01*
X77939Y-135179D01*
X78539Y-134979D01*
X79439Y-135379D01*
X80039Y-136179D01*
X80439Y-137579D01*
Y-139179D01*
X80239Y-140779D01*
X79839Y-141979D01*
X79139Y-142779D01*
X78539Y-142979D01*
X77939Y-142779D01*
X77339Y-142179D01*
X76839Y-141179D01*
G01X83139Y-137579D02*
X86339D01*
X86039Y-136179D01*
X85539Y-135379D01*
X84839Y-134979D01*
X84139Y-135179D01*
X83539Y-135779D01*
X83139Y-137179D01*
X82939Y-138379D01*
Y-139579D01*
X83139Y-140779D01*
X83639Y-141979D01*
X84239Y-142779D01*
X84939Y-142979D01*
X85639Y-142579D01*
X86339Y-141379D01*
G01X89239Y-142979D02*
Y-134979D01*
G01Y-136579D02*
X89739Y-135779D01*
X90239Y-135179D01*
X90939Y-134979D01*
X91439Y-135179D01*
X92039Y-135779D01*
G01X102639Y-134979D02*
Y-142979D01*
G01Y-131779D02*
X102439Y-131579D01*
Y-131179D01*
X102639Y-130979D01*
X102839Y-131179D01*
Y-131579D01*
X102639Y-131779D01*
G01X107139Y-141579D02*
X107639Y-142379D01*
X108339Y-142979D01*
X108939D01*
X109539Y-142579D01*
X109939Y-141979D01*
X110139Y-141179D01*
X110039Y-139979D01*
X109639Y-139379D01*
X107839Y-138179D01*
X107439Y-136779D01*
X107639Y-135779D01*
X108039Y-135179D01*
X108639Y-134979D01*
X109239Y-135179D01*
X109839Y-135779D01*
G01X119039Y-145979D02*
X119739Y-146779D01*
X120339Y-146979D01*
X121139Y-146579D01*
X121739Y-145579D01*
X122039Y-143779D01*
Y-134979D01*
G01Y-131779D02*
X121839Y-131579D01*
Y-131179D01*
X122039Y-130979D01*
X122239Y-131179D01*
Y-131579D01*
X122039Y-131779D01*
G01X124939Y-134979D02*
Y-140579D01*
X125339Y-141979D01*
X125939Y-142779D01*
X126639Y-142979D01*
X127339Y-142779D01*
X127939Y-141979D01*
X128339Y-140579D01*
G01Y-142979D02*
Y-134979D01*
G01X131139Y-141579D02*
X131639Y-142379D01*
X132339Y-142979D01*
X132939D01*
X133539Y-142579D01*
X133939Y-141979D01*
X134139Y-141179D01*
X134039Y-139979D01*
X133639Y-139379D01*
X131839Y-138179D01*
X131439Y-136779D01*
X131639Y-135779D01*
X132039Y-135179D01*
X132639Y-134979D01*
X133239Y-135179D01*
X133839Y-135779D01*
G01X138639Y-130979D02*
Y-142979D01*
G01X137239Y-134979D02*
X140039D01*
G01X150039Y-142979D02*
Y-132779D01*
X150239Y-131779D01*
X150639Y-131179D01*
X151239Y-130979D01*
X151839Y-131379D01*
X152139Y-132379D01*
G01X150939Y-135779D02*
X148939D01*
G01X156639Y-142979D02*
X156039Y-142779D01*
X155439Y-141979D01*
X155039Y-140579D01*
X154839Y-138979D01*
X155039Y-137379D01*
X155439Y-135979D01*
X156039Y-135179D01*
X156639Y-134979D01*
X157239Y-135179D01*
X157839Y-135979D01*
X158239Y-137379D01*
X158339Y-138979D01*
X158239Y-140579D01*
X157839Y-141979D01*
X157239Y-142779D01*
X156639Y-142979D01*
G01X161239D02*
Y-134979D01*
G01Y-136579D02*
X161739Y-135779D01*
X162239Y-135179D01*
X162939Y-134979D01*
X163439Y-135179D01*
X164039Y-135779D01*
G01X172539Y-146579D02*
X173139Y-146979D01*
X173939Y-146579D01*
X174439Y-145779D01*
X174839Y-144779D01*
X175439Y-141579D01*
X176739Y-134979D01*
G01X173539D02*
X175439Y-141579D01*
G01X180639Y-142979D02*
X180039Y-142779D01*
X179439Y-141979D01*
X179039Y-140579D01*
X178839Y-138979D01*
X179039Y-137379D01*
X179439Y-135979D01*
X180039Y-135179D01*
X180639Y-134979D01*
X181239Y-135179D01*
X181839Y-135979D01*
X182239Y-137379D01*
X182339Y-138979D01*
X182239Y-140579D01*
X181839Y-141979D01*
X181239Y-142779D01*
X180639Y-142979D01*
G01X184939Y-134979D02*
Y-140579D01*
X185339Y-141979D01*
X185939Y-142779D01*
X186639Y-142979D01*
X187339Y-142779D01*
X187939Y-141979D01*
X188339Y-140579D01*
G01Y-142979D02*
Y-134979D01*
G01X197239Y-142979D02*
Y-134979D01*
G01Y-136579D02*
X197739Y-135779D01*
X198239Y-135179D01*
X198939Y-134979D01*
X199439Y-135179D01*
X200039Y-135779D01*
G01X203139Y-137579D02*
X206339D01*
X206039Y-136179D01*
X205539Y-135379D01*
X204839Y-134979D01*
X204139Y-135179D01*
X203539Y-135779D01*
X203139Y-137179D01*
X202939Y-138379D01*
Y-139579D01*
X203139Y-140779D01*
X203639Y-141979D01*
X204239Y-142779D01*
X204939Y-142979D01*
X205639Y-142579D01*
X206339Y-141379D01*
G01X210039Y-142979D02*
Y-132779D01*
X210239Y-131779D01*
X210639Y-131179D01*
X211239Y-130979D01*
X211839Y-131379D01*
X212139Y-132379D01*
G01X210939Y-135779D02*
X208939D01*
G01X215139Y-137579D02*
X218339D01*
X218039Y-136179D01*
X217539Y-135379D01*
X216839Y-134979D01*
X216139Y-135179D01*
X215539Y-135779D01*
X215139Y-137179D01*
X214939Y-138379D01*
Y-139579D01*
X215139Y-140779D01*
X215639Y-141979D01*
X216239Y-142779D01*
X216939Y-142979D01*
X217639Y-142579D01*
X218339Y-141379D01*
G01X221239Y-142979D02*
Y-134979D01*
G01Y-136579D02*
X221739Y-135779D01*
X222239Y-135179D01*
X222939Y-134979D01*
X223439Y-135179D01*
X224039Y-135779D01*
G01X227139Y-137579D02*
X230339D01*
X230039Y-136179D01*
X229539Y-135379D01*
X228839Y-134979D01*
X228139Y-135179D01*
X227539Y-135779D01*
X227139Y-137179D01*
X226939Y-138379D01*
Y-139579D01*
X227139Y-140779D01*
X227639Y-141979D01*
X228239Y-142779D01*
X228939Y-142979D01*
X229639Y-142579D01*
X230339Y-141379D01*
G01X232939Y-142979D02*
Y-134979D01*
G01Y-136979D02*
X233339Y-135979D01*
X233939Y-135179D01*
X234739Y-134979D01*
X235439Y-135179D01*
X236039Y-135979D01*
X236339Y-137379D01*
Y-142979D01*
G01X242239Y-135979D02*
X241539Y-135179D01*
X240939Y-134979D01*
X240139Y-135379D01*
X239539Y-136179D01*
X239139Y-137579D01*
X239039Y-138979D01*
X239139Y-140379D01*
X239539Y-141579D01*
X240139Y-142579D01*
X240939Y-142979D01*
X241639Y-142579D01*
X242239Y-141779D01*
G01X245139Y-137579D02*
X248339D01*
X248039Y-136179D01*
X247539Y-135379D01*
X246839Y-134979D01*
X246139Y-135179D01*
X245539Y-135779D01*
X245139Y-137179D01*
X244939Y-138379D01*
Y-139579D01*
X245139Y-140779D01*
X245639Y-141979D01*
X246239Y-142779D01*
X246939Y-142979D01*
X247639Y-142579D01*
X248339Y-141379D01*
G01X258639Y-130979D02*
Y-142979D01*
G01X257239Y-134979D02*
X260039D01*
G01X264639Y-142979D02*
X264039Y-142779D01*
X263439Y-141979D01*
X263039Y-140579D01*
X262839Y-138979D01*
X263039Y-137379D01*
X263439Y-135979D01*
X264039Y-135179D01*
X264639Y-134979D01*
X265239Y-135179D01*
X265839Y-135979D01*
X266239Y-137379D01*
X266339Y-138979D01*
X266239Y-140579D01*
X265839Y-141979D01*
X265239Y-142779D01*
X264639Y-142979D01*
G01X276039D02*
Y-132779D01*
X276239Y-131779D01*
X276639Y-131179D01*
X277239Y-130979D01*
X277839Y-131379D01*
X278139Y-132379D01*
G01X276939Y-135779D02*
X274939D01*
G01X282639Y-134979D02*
Y-142979D01*
G01Y-131779D02*
X282439Y-131579D01*
Y-131179D01*
X282639Y-130979D01*
X282839Y-131179D01*
Y-131579D01*
X282639Y-131779D01*
G01X286939Y-142979D02*
Y-134979D01*
G01Y-136979D02*
X287339Y-135979D01*
X287939Y-135179D01*
X288739Y-134979D01*
X289439Y-135179D01*
X290039Y-135979D01*
X290339Y-137379D01*
Y-142979D01*
G01X296439Y-130979D02*
Y-142979D01*
G01Y-141179D02*
X296039Y-142179D01*
X295439Y-142779D01*
X294739Y-142979D01*
X293939Y-142579D01*
X293339Y-141579D01*
X292939Y-140379D01*
X292839Y-138979D01*
X292939Y-137579D01*
X293339Y-136379D01*
X293939Y-135379D01*
X294739Y-134979D01*
X295439Y-135179D01*
X295939Y-135579D01*
X296439Y-136379D01*
G01X306639Y-130979D02*
Y-142979D01*
G01X305239Y-134979D02*
X308039D01*
G01X310939Y-142979D02*
Y-130979D01*
G01Y-136779D02*
X311439Y-135779D01*
X311939Y-135179D01*
X312739Y-134979D01*
X313339Y-135179D01*
X314039Y-135979D01*
X314339Y-137179D01*
Y-142979D01*
G01X317139Y-137579D02*
X320339D01*
X320039Y-136179D01*
X319539Y-135379D01*
X318839Y-134979D01*
X318139Y-135179D01*
X317539Y-135779D01*
X317139Y-137179D01*
X316939Y-138379D01*
Y-139579D01*
X317139Y-140779D01*
X317639Y-141979D01*
X318239Y-142779D01*
X318939Y-142979D01*
X319639Y-142579D01*
X320339Y-141379D01*
G01X332439Y-130979D02*
Y-142979D01*
G01Y-141179D02*
X332039Y-142179D01*
X331439Y-142779D01*
X330739Y-142979D01*
X329939Y-142579D01*
X329339Y-141579D01*
X328939Y-140379D01*
X328839Y-138979D01*
X328939Y-137579D01*
X329339Y-136379D01*
X329939Y-135379D01*
X330739Y-134979D01*
X331439Y-135179D01*
X331939Y-135579D01*
X332439Y-136379D01*
G01X336639Y-134979D02*
Y-142979D01*
G01Y-131779D02*
X336439Y-131579D01*
Y-131179D01*
X336639Y-130979D01*
X336839Y-131179D01*
Y-131579D01*
X336639Y-131779D01*
G01X342039Y-142979D02*
Y-132779D01*
X342239Y-131779D01*
X342639Y-131179D01*
X343239Y-130979D01*
X343839Y-131379D01*
X344139Y-132379D01*
G01X342939Y-135779D02*
X340939D01*
G01X348039Y-142979D02*
Y-132779D01*
X348239Y-131779D01*
X348639Y-131179D01*
X349239Y-130979D01*
X349839Y-131379D01*
X350139Y-132379D01*
G01X348939Y-135779D02*
X346939D01*
G01X353139Y-137579D02*
X356339D01*
X356039Y-136179D01*
X355539Y-135379D01*
X354839Y-134979D01*
X354139Y-135179D01*
X353539Y-135779D01*
X353139Y-137179D01*
X352939Y-138379D01*
Y-139579D01*
X353139Y-140779D01*
X353639Y-141979D01*
X354239Y-142779D01*
X354939Y-142979D01*
X355639Y-142579D01*
X356339Y-141379D01*
G01X359239Y-142979D02*
Y-134979D01*
G01Y-136579D02*
X359739Y-135779D01*
X360239Y-135179D01*
X360939Y-134979D01*
X361439Y-135179D01*
X362039Y-135779D01*
G01X365139Y-137579D02*
X368339D01*
X368039Y-136179D01*
X367539Y-135379D01*
X366839Y-134979D01*
X366139Y-135179D01*
X365539Y-135779D01*
X365139Y-137179D01*
X364939Y-138379D01*
Y-139579D01*
X365139Y-140779D01*
X365639Y-141979D01*
X366239Y-142779D01*
X366939Y-142979D01*
X367639Y-142579D01*
X368339Y-141379D01*
G01X370939Y-142979D02*
Y-134979D01*
G01Y-136979D02*
X371339Y-135979D01*
X371939Y-135179D01*
X372739Y-134979D01*
X373439Y-135179D01*
X374039Y-135979D01*
X374339Y-137379D01*
Y-142979D01*
G01X378639Y-130979D02*
Y-142979D01*
G01X377239Y-134979D02*
X380039D01*
G01X384639D02*
Y-142979D01*
G01Y-131779D02*
X384439Y-131579D01*
Y-131179D01*
X384639Y-130979D01*
X384839Y-131179D01*
Y-131579D01*
X384639Y-131779D01*
G01X392439Y-142979D02*
Y-134979D01*
G01Y-136379D02*
X392039Y-135579D01*
X391439Y-135179D01*
X390739Y-134979D01*
X390039Y-135379D01*
X389439Y-136179D01*
X389039Y-137379D01*
X388839Y-138979D01*
X389039Y-140579D01*
X389439Y-141779D01*
X390039Y-142579D01*
X390739Y-142979D01*
X391439Y-142779D01*
X392039Y-142179D01*
X392439Y-141379D01*
G01X396639Y-142979D02*
Y-130979D01*
G01X408639D02*
Y-142979D01*
G01X407239Y-134979D02*
X410039D01*
G01X413239Y-142979D02*
Y-134979D01*
G01Y-136579D02*
X413739Y-135779D01*
X414239Y-135179D01*
X414939Y-134979D01*
X415439Y-135179D01*
X416039Y-135779D01*
G01X422439Y-142979D02*
Y-134979D01*
G01Y-136379D02*
X422039Y-135579D01*
X421439Y-135179D01*
X420739Y-134979D01*
X420039Y-135379D01*
X419439Y-136179D01*
X419039Y-137379D01*
X418839Y-138979D01*
X419039Y-140579D01*
X419439Y-141779D01*
X420039Y-142579D01*
X420739Y-142979D01*
X421439Y-142779D01*
X422039Y-142179D01*
X422439Y-141379D01*
G01X428239Y-135979D02*
X427539Y-135179D01*
X426939Y-134979D01*
X426139Y-135379D01*
X425539Y-136179D01*
X425139Y-137579D01*
X425039Y-138979D01*
X425139Y-140379D01*
X425539Y-141579D01*
X426139Y-142579D01*
X426939Y-142979D01*
X427639Y-142579D01*
X428239Y-141779D01*
G01X431139Y-137579D02*
X434339D01*
X434039Y-136179D01*
X433539Y-135379D01*
X432839Y-134979D01*
X432139Y-135179D01*
X431539Y-135779D01*
X431139Y-137179D01*
X430939Y-138379D01*
Y-139579D01*
X431139Y-140779D01*
X431639Y-141979D01*
X432239Y-142779D01*
X432939Y-142979D01*
X433639Y-142579D01*
X434339Y-141379D01*
G01X437139Y-141579D02*
X437639Y-142379D01*
X438339Y-142979D01*
X438939D01*
X439539Y-142579D01*
X439939Y-141979D01*
X440139Y-141179D01*
X440039Y-139979D01*
X439639Y-139379D01*
X437839Y-138179D01*
X437439Y-136779D01*
X437639Y-135779D01*
X438039Y-135179D01*
X438639Y-134979D01*
X439239Y-135179D01*
X439839Y-135779D01*
G01X450639Y-134979D02*
Y-142979D01*
G01Y-131779D02*
X450439Y-131579D01*
Y-131179D01*
X450639Y-130979D01*
X450839Y-131179D01*
Y-131579D01*
X450639Y-131779D01*
G01X454939Y-142979D02*
Y-134979D01*
G01Y-136979D02*
X455339Y-135979D01*
X455939Y-135179D01*
X456739Y-134979D01*
X457439Y-135179D01*
X458039Y-135979D01*
X458339Y-137379D01*
Y-142979D01*
G01X468639D02*
Y-130979D01*
G01X476439Y-142979D02*
Y-134979D01*
G01Y-136379D02*
X476039Y-135579D01*
X475439Y-135179D01*
X474739Y-134979D01*
X474039Y-135379D01*
X473439Y-136179D01*
X473039Y-137379D01*
X472839Y-138979D01*
X473039Y-140579D01*
X473439Y-141779D01*
X474039Y-142579D01*
X474739Y-142979D01*
X475439Y-142779D01*
X476039Y-142179D01*
X476439Y-141379D01*
G01X478539Y-146579D02*
X479139Y-146979D01*
X479939Y-146579D01*
X480439Y-145779D01*
X480839Y-144779D01*
X481439Y-141579D01*
X482739Y-134979D01*
G01X479539D02*
X481439Y-141579D01*
G01X485139Y-137579D02*
X488339D01*
X488039Y-136179D01*
X487539Y-135379D01*
X486839Y-134979D01*
X486139Y-135179D01*
X485539Y-135779D01*
X485139Y-137179D01*
X484939Y-138379D01*
Y-139579D01*
X485139Y-140779D01*
X485639Y-141979D01*
X486239Y-142779D01*
X486939Y-142979D01*
X487639Y-142579D01*
X488339Y-141379D01*
G01X491239Y-142979D02*
Y-134979D01*
G01Y-136579D02*
X491739Y-135779D01*
X492239Y-135179D01*
X492939Y-134979D01*
X493439Y-135179D01*
X494039Y-135779D01*
G01X505439Y-136579D02*
X505839Y-135979D01*
X506139Y-134979D01*
X506339Y-133579D01*
X506139Y-132379D01*
X505739Y-131579D01*
X505039Y-130979D01*
X502339D01*
Y-142979D01*
X505639D01*
X506339Y-142179D01*
X506739Y-140979D01*
X506939Y-139579D01*
X506739Y-138179D01*
X506139Y-136979D01*
X505439Y-136579D01*
X502339D01*
G01X510639Y-142979D02*
X509839Y-142779D01*
X509139Y-141979D01*
X508539Y-140779D01*
X508139Y-139379D01*
X507939Y-137779D01*
Y-136179D01*
X508139Y-134579D01*
X508539Y-133179D01*
X509139Y-131979D01*
X509839Y-131179D01*
X510639Y-130979D01*
X511439Y-131179D01*
X512139Y-131979D01*
X512739Y-133179D01*
X513139Y-134579D01*
X513339Y-136179D01*
Y-137779D01*
X513139Y-139379D01*
X512739Y-140779D01*
X512139Y-141979D01*
X511439Y-142779D01*
X510639Y-142979D01*
G01X516639Y-130979D02*
Y-142979D01*
G01X514339Y-130979D02*
X518939D01*
G01X522639D02*
Y-142979D01*
G01X520339Y-130979D02*
X524939D01*
G01X528639Y-142979D02*
X527839Y-142779D01*
X527139Y-141979D01*
X526539Y-140779D01*
X526139Y-139379D01*
X525939Y-137779D01*
Y-136179D01*
X526139Y-134579D01*
X526539Y-133179D01*
X527139Y-131979D01*
X527839Y-131179D01*
X528639Y-130979D01*
X529439Y-131179D01*
X530139Y-131979D01*
X530739Y-133179D01*
X531139Y-134579D01*
X531339Y-136179D01*
Y-137779D01*
X531139Y-139379D01*
X530739Y-140779D01*
X530139Y-141979D01*
X529439Y-142779D01*
X528639Y-142979D01*
G01X532039D02*
Y-130979D01*
X534639Y-140979D01*
X537239Y-130979D01*
Y-142979D01*
G01X36516Y309567D02*
G02X22539I-6989J0D01*
G02X36516I6989J0D01*
G01Y1029528D02*
G02X22539I-6989J0D01*
G02X36516I6989J0D01*
G01X137795Y17717D02*
G02X122047I-7874J0D01*
G02X137795I7874J0D01*
G01X278642Y267717D02*
G02X264665I-6989J0D01*
G02X278642I6988J0D01*
G01Y673228D02*
G02X264665I-6989J0D01*
G02X278642I6988J0D01*
G01Y1078740D02*
G02X264665I-6989J0D01*
G02X278642I6988J0D01*
G01Y1484252D02*
G02X264665I-6989J0D01*
G02X278642I6988J0D01*
G01Y1889764D02*
G02X264665I-6989J0D01*
G02X278642I6988J0D01*
G01X1001083Y149606D02*
G02X987106I-6989J0D01*
G02X1001083I6988J0D01*
G01Y673228D02*
G02X987106I-6989J0D01*
G02X1001083I6988J0D01*
G01Y1068898D02*
G02X987106I-6989J0D01*
G02X1001083I6988J0D01*
G01X1001969Y1889764D02*
G02X986220I-7875J0D01*
G02X1001969I7874J0D01*
G01X1012008Y1416024D02*
G02X1026575I7284J0D01*
G02X1012008I-7283J0D01*
G01Y1694213D02*
G02X1026575I7284J0D01*
G02X1012008I-7283J0D01*
M02*
